(kicad_sch
	(version 20250114)
	(generator "eeschema")
	(generator_version "9.0")
	(paper "A3")
	(title_block
		(title "PolarFire SoM")
		(date "2025-07-22")
		(rev "1.1.4")
		(company "Antmicro Ltd")
		(comment 1 "www.antmicro.com")
	)
	(text "GND*"
		(exclude_from_sim no)
		(at 118.11 243.84 0)
		(effects
			(font
				(size 1.27 1.27)
			)
			(justify left bottom)
		)
	)
	(text "3V3"
		(exclude_from_sim no)
		(at 118.11 248.92 0)
		(effects
			(font
				(size 1.27 1.27)
			)
			(justify left bottom)
		)
	)
	(text "Memory supply logic"
		(exclude_from_sim no)
		(at 59.055 175.26 0)
		(effects
			(font
				(size 4 4)
				(thickness 0.8)
				(bold yes)
			)
			(justify left bottom)
		)
	)
	(text "3V3*"
		(exclude_from_sim no)
		(at 140.97 243.84 0)
		(effects
			(font
				(size 1.27 1.27)
			)
			(justify left bottom)
		)
	)
	(text "1V8"
		(exclude_from_sim no)
		(at 140.97 248.92 0)
		(effects
			(font
				(size 1.27 1.27)
			)
			(justify left bottom)
		)
	)
	(text "SD_VDD_OVERRIDE"
		(exclude_from_sim no)
		(at 113.03 238.76 0)
		(effects
			(font
				(size 1.27 1.27)
			)
			(justify left bottom)
		)
	)
	(text "Memory signaling"
		(exclude_from_sim no)
		(at 134.62 238.76 0)
		(effects
			(font
				(size 1.27 1.27)
			)
			(justify left bottom)
		)
	)
	(text "eMMC"
		(exclude_from_sim no)
		(at 16.51 21.59 0)
		(effects
			(font
				(size 4 4)
				(thickness 0.8)
				(bold yes)
			)
			(justify left bottom)
		)
	)
	(junction
		(at 237.49 106.68)
		(diameter 0)
		(color 0 0 0 0)
	)
	(junction
		(at 242.57 72.39)
		(diameter 0)
		(color 0 0 0 0)
	)
	(junction
		(at 203.2 99.06)
		(diameter 0)
		(color 0 0 0 0)
	)
	(junction
		(at 232.41 111.76)
		(diameter 0)
		(color 0 0 0 0)
	)
	(junction
		(at 152.4 130.81)
		(diameter 0)
		(color 0 0 0 0)
	)
	(junction
		(at 237.49 72.39)
		(diameter 0)
		(color 0 0 0 0)
	)
	(junction
		(at 232.41 109.22)
		(diameter 0)
		(color 0 0 0 0)
	)
	(junction
		(at 252.73 91.44)
		(diameter 0)
		(color 0 0 0 0)
	)
	(junction
		(at 157.48 76.2)
		(diameter 0)
		(color 0 0 0 0)
	)
	(junction
		(at 63.5 240.03)
		(diameter 0)
		(color 0 0 0 0)
	)
	(junction
		(at 62.23 208.28)
		(diameter 0)
		(color 0 0 0 0)
	)
	(junction
		(at 247.65 96.52)
		(diameter 0)
		(color 0 0 0 0)
	)
	(junction
		(at 252.73 72.39)
		(diameter 0)
		(color 0 0 0 0)
	)
	(junction
		(at 92.71 203.2)
		(diameter 0)
		(color 0 0 0 0)
	)
	(junction
		(at 245.11 99.06)
		(diameter 0)
		(color 0 0 0 0)
	)
	(junction
		(at 151.13 64.77)
		(diameter 0)
		(color 0 0 0 0)
	)
	(junction
		(at 240.03 72.39)
		(diameter 0)
		(color 0 0 0 0)
	)
	(junction
		(at 247.65 72.39)
		(diameter 0)
		(color 0 0 0 0)
	)
	(junction
		(at 146.05 130.81)
		(diameter 0)
		(color 0 0 0 0)
	)
	(junction
		(at 242.57 101.6)
		(diameter 0)
		(color 0 0 0 0)
	)
	(junction
		(at 128.27 213.36)
		(diameter 0)
		(color 0 0 0 0)
	)
	(junction
		(at 255.27 88.9)
		(diameter 0)
		(color 0 0 0 0)
	)
	(junction
		(at 165.1 119.38)
		(diameter 0)
		(color 0 0 0 0)
	)
	(junction
		(at 157.48 64.77)
		(diameter 0)
		(color 0 0 0 0)
	)
	(junction
		(at 144.78 76.2)
		(diameter 0)
		(color 0 0 0 0)
	)
	(junction
		(at 144.78 64.77)
		(diameter 0)
		(color 0 0 0 0)
	)
	(junction
		(at 152.4 119.38)
		(diameter 0)
		(color 0 0 0 0)
	)
	(junction
		(at 250.19 93.98)
		(diameter 0)
		(color 0 0 0 0)
	)
	(junction
		(at 151.13 76.2)
		(diameter 0)
		(color 0 0 0 0)
	)
	(junction
		(at 245.11 72.39)
		(diameter 0)
		(color 0 0 0 0)
	)
	(junction
		(at 203.2 123.19)
		(diameter 0)
		(color 0 0 0 0)
	)
	(junction
		(at 158.75 130.81)
		(diameter 0)
		(color 0 0 0 0)
	)
	(junction
		(at 240.03 104.14)
		(diameter 0)
		(color 0 0 0 0)
	)
	(junction
		(at 250.19 72.39)
		(diameter 0)
		(color 0 0 0 0)
	)
	(junction
		(at 232.41 72.39)
		(diameter 0)
		(color 0 0 0 0)
	)
	(junction
		(at 57.15 205.74)
		(diameter 0)
		(color 0 0 0 0)
	)
	(junction
		(at 158.75 119.38)
		(diameter 0)
		(color 0 0 0 0)
	)
	(no_connect
		(at 83.82 234.95)
	)
	(bus_entry
		(at 267.97 104.14)
		(size 2.54 -2.54)
		(stroke
			(width 0)
			(type default)
		)
	)
	(bus_entry
		(at 189.23 99.06)
		(size -2.54 -2.54)
		(stroke
			(width 0)
			(type default)
		)
	)
	(bus_entry
		(at 267.97 109.22)
		(size 2.54 -2.54)
		(stroke
			(width 0)
			(type default)
		)
	)
	(bus_entry
		(at 267.97 101.6)
		(size 2.54 -2.54)
		(stroke
			(width 0)
			(type default)
		)
	)
	(bus_entry
		(at 267.97 106.68)
		(size 2.54 -2.54)
		(stroke
			(width 0)
			(type default)
		)
	)
	(bus_entry
		(at 267.97 99.06)
		(size 2.54 -2.54)
		(stroke
			(width 0)
			(type default)
		)
	)
	(bus_entry
		(at 267.97 88.9)
		(size 2.54 -2.54)
		(stroke
			(width 0)
			(type default)
		)
	)
	(bus_entry
		(at 267.97 111.76)
		(size 2.54 -2.54)
		(stroke
			(width 0)
			(type default)
		)
	)
	(bus_entry
		(at 267.97 93.98)
		(size 2.54 -2.54)
		(stroke
			(width 0)
			(type default)
		)
	)
	(bus_entry
		(at 267.97 96.52)
		(size 2.54 -2.54)
		(stroke
			(width 0)
			(type default)
		)
	)
	(bus_entry
		(at 189.23 96.52)
		(size -2.54 -2.54)
		(stroke
			(width 0)
			(type default)
		)
	)
	(bus_entry
		(at 267.97 91.44)
		(size 2.54 -2.54)
		(stroke
			(width 0)
			(type default)
		)
	)
	(wire
		(pts
			(xy 232.41 82.55) (xy 232.41 109.22)
		)
		(stroke
			(width 0)
			(type default)
		)
	)
	(wire
		(pts
			(xy 229.87 93.98) (xy 250.19 93.98)
		)
		(stroke
			(width 0)
			(type default)
		)
	)
	(wire
		(pts
			(xy 146.05 127) (xy 146.05 130.81)
		)
		(stroke
			(width 0)
			(type default)
		)
	)
	(wire
		(pts
			(xy 92.71 195.58) (xy 92.71 194.31)
		)
		(stroke
			(width 0)
			(type default)
		)
	)
	(wire
		(pts
			(xy 229.87 99.06) (xy 245.11 99.06)
		)
		(stroke
			(width 0)
			(type default)
		)
	)
	(wire
		(pts
			(xy 128.27 198.12) (xy 128.27 207.01)
		)
		(stroke
			(width 0)
			(type default)
		)
	)
	(polyline
		(pts
			(xy 111.76 234.95) (xy 111.76 240.03)
		)
		(stroke
			(width 0)
			(type default)
		)
	)
	(wire
		(pts
			(xy 83.82 208.28) (xy 86.36 208.28)
		)
		(stroke
			(width 0)
			(type default)
		)
	)
	(wire
		(pts
			(xy 203.2 99.06) (xy 205.74 99.06)
		)
		(stroke
			(width 0)
			(type default)
		)
	)
	(wire
		(pts
			(xy 128.27 213.36) (xy 128.27 214.63)
		)
		(stroke
			(width 0)
			(type default)
		)
	)
	(wire
		(pts
			(xy 203.2 123.19) (xy 203.2 127)
		)
		(stroke
			(width 0)
			(type default)
		)
	)
	(wire
		(pts
			(xy 140.97 76.2) (xy 144.78 76.2)
		)
		(stroke
			(width 0)
			(type default)
		)
	)
	(wire
		(pts
			(xy 35.56 240.03) (xy 63.5 240.03)
		)
		(stroke
			(width 0)
			(type default)
		)
	)
	(wire
		(pts
			(xy 157.48 64.77) (xy 163.83 64.77)
		)
		(stroke
			(width 0)
			(type default)
		)
	)
	(bus
		(pts
			(xy 270.51 93.98) (xy 270.51 96.52)
		)
		(stroke
			(width 0)
			(type default)
		)
	)
	(wire
		(pts
			(xy 157.48 72.39) (xy 157.48 76.2)
		)
		(stroke
			(width 0)
			(type default)
		)
	)
	(wire
		(pts
			(xy 100.33 232.41) (xy 95.25 232.41)
		)
		(stroke
			(width 0)
			(type default)
		)
	)
	(wire
		(pts
			(xy 237.49 72.39) (xy 240.03 72.39)
		)
		(stroke
			(width 0)
			(type default)
		)
	)
	(wire
		(pts
			(xy 165.1 127) (xy 165.1 130.81)
		)
		(stroke
			(width 0)
			(type default)
		)
	)
	(wire
		(pts
			(xy 229.87 111.76) (xy 232.41 111.76)
		)
		(stroke
			(width 0)
			(type default)
		)
	)
	(wire
		(pts
			(xy 205.74 120.65) (xy 203.2 120.65)
		)
		(stroke
			(width 0)
			(type default)
		)
	)
	(wire
		(pts
			(xy 229.87 91.44) (xy 252.73 91.44)
		)
		(stroke
			(width 0)
			(type default)
		)
	)
	(wire
		(pts
			(xy 232.41 72.39) (xy 232.41 77.47)
		)
		(stroke
			(width 0)
			(type default)
		)
	)
	(wire
		(pts
			(xy 247.65 72.39) (xy 247.65 77.47)
		)
		(stroke
			(width 0)
			(type default)
		)
	)
	(wire
		(pts
			(xy 31.75 205.74) (xy 31.75 208.28)
		)
		(stroke
			(width 0)
			(type default)
		)
	)
	(wire
		(pts
			(xy 86.36 208.28) (xy 86.36 209.55)
		)
		(stroke
			(width 0)
			(type default)
		)
	)
	(bus
		(pts
			(xy 271.78 83.82) (xy 270.51 85.09)
		)
		(stroke
			(width 0)
			(type default)
		)
	)
	(wire
		(pts
			(xy 203.2 80.01) (xy 203.2 99.06)
		)
		(stroke
			(width 0)
			(type default)
		)
	)
	(wire
		(pts
			(xy 152.4 119.38) (xy 158.75 119.38)
		)
		(stroke
			(width 0)
			(type default)
		)
	)
	(wire
		(pts
			(xy 247.65 72.39) (xy 250.19 72.39)
		)
		(stroke
			(width 0)
			(type default)
		)
	)
	(wire
		(pts
			(xy 151.13 64.77) (xy 151.13 67.31)
		)
		(stroke
			(width 0)
			(type default)
		)
	)
	(wire
		(pts
			(xy 66.04 234.95) (xy 63.5 234.95)
		)
		(stroke
			(width 0)
			(type default)
		)
	)
	(polyline
		(pts
			(xy 111.76 245.11) (xy 152.4 245.11)
		)
		(stroke
			(width 0)
			(type default)
		)
	)
	(wire
		(pts
			(xy 128.27 212.09) (xy 128.27 213.36)
		)
		(stroke
			(width 0)
			(type default)
		)
	)
	(polyline
		(pts
			(xy 111.76 250.19) (xy 152.4 250.19)
		)
		(stroke
			(width 0)
			(type default)
		)
	)
	(wire
		(pts
			(xy 158.75 127) (xy 158.75 130.81)
		)
		(stroke
			(width 0)
			(type default)
		)
	)
	(wire
		(pts
			(xy 203.2 120.65) (xy 203.2 123.19)
		)
		(stroke
			(width 0)
			(type default)
		)
	)
	(polyline
		(pts
			(xy 152.4 240.03) (xy 152.4 250.19)
		)
		(stroke
			(width 0)
			(type default)
		)
	)
	(wire
		(pts
			(xy 58.42 237.49) (xy 66.04 237.49)
		)
		(stroke
			(width 0)
			(type default)
		)
	)
	(wire
		(pts
			(xy 158.75 119.38) (xy 158.75 121.92)
		)
		(stroke
			(width 0)
			(type default)
		)
	)
	(wire
		(pts
			(xy 252.73 91.44) (xy 267.97 91.44)
		)
		(stroke
			(width 0)
			(type default)
		)
	)
	(wire
		(pts
			(xy 151.13 64.77) (xy 157.48 64.77)
		)
		(stroke
			(width 0)
			(type default)
		)
	)
	(bus
		(pts
			(xy 270.51 88.9) (xy 270.51 91.44)
		)
		(stroke
			(width 0)
			(type default)
		)
	)
	(wire
		(pts
			(xy 146.05 130.81) (xy 152.4 130.81)
		)
		(stroke
			(width 0)
			(type default)
		)
	)
	(wire
		(pts
			(xy 83.82 203.2) (xy 92.71 203.2)
		)
		(stroke
			(width 0)
			(type default)
		)
	)
	(bus
		(pts
			(xy 271.78 83.82) (xy 273.05 83.82)
		)
		(stroke
			(width 0)
			(type default)
		)
	)
	(wire
		(pts
			(xy 165.1 119.38) (xy 165.1 121.92)
		)
		(stroke
			(width 0)
			(type default)
		)
	)
	(wire
		(pts
			(xy 255.27 72.39) (xy 255.27 77.47)
		)
		(stroke
			(width 0)
			(type default)
		)
	)
	(polyline
		(pts
			(xy 132.08 234.95) (xy 132.08 250.19)
		)
		(stroke
			(width 0)
			(type default)
		)
	)
	(wire
		(pts
			(xy 152.4 130.81) (xy 158.75 130.81)
		)
		(stroke
			(width 0)
			(type default)
		)
	)
	(polyline
		(pts
			(xy 111.76 240.03) (xy 111.76 250.19)
		)
		(stroke
			(width 0)
			(type default)
		)
	)
	(wire
		(pts
			(xy 252.73 72.39) (xy 252.73 77.47)
		)
		(stroke
			(width 0)
			(type default)
		)
	)
	(wire
		(pts
			(xy 158.75 119.38) (xy 165.1 119.38)
		)
		(stroke
			(width 0)
			(type default)
		)
	)
	(bus
		(pts
			(xy 186.69 91.44) (xy 186.69 93.98)
		)
		(stroke
			(width 0)
			(type default)
		)
	)
	(wire
		(pts
			(xy 128.27 219.71) (xy 128.27 220.98)
		)
		(stroke
			(width 0)
			(type default)
		)
	)
	(wire
		(pts
			(xy 175.26 53.34) (xy 175.26 67.31)
		)
		(stroke
			(width 0)
			(type default)
		)
	)
	(wire
		(pts
			(xy 240.03 82.55) (xy 240.03 104.14)
		)
		(stroke
			(width 0)
			(type default)
		)
	)
	(wire
		(pts
			(xy 144.78 76.2) (xy 151.13 76.2)
		)
		(stroke
			(width 0)
			(type default)
		)
	)
	(wire
		(pts
			(xy 191.77 93.98) (xy 205.74 93.98)
		)
		(stroke
			(width 0)
			(type default)
		)
	)
	(wire
		(pts
			(xy 63.5 234.95) (xy 63.5 240.03)
		)
		(stroke
			(width 0)
			(type default)
		)
	)
	(wire
		(pts
			(xy 232.41 62.23) (xy 232.41 72.39)
		)
		(stroke
			(width 0)
			(type default)
		)
	)
	(wire
		(pts
			(xy 237.49 72.39) (xy 237.49 77.47)
		)
		(stroke
			(width 0)
			(type default)
		)
	)
	(wire
		(pts
			(xy 189.23 99.06) (xy 203.2 99.06)
		)
		(stroke
			(width 0)
			(type default)
		)
	)
	(wire
		(pts
			(xy 57.15 209.55) (xy 57.15 205.74)
		)
		(stroke
			(width 0)
			(type default)
		)
	)
	(wire
		(pts
			(xy 237.49 82.55) (xy 237.49 106.68)
		)
		(stroke
			(width 0)
			(type default)
		)
	)
	(wire
		(pts
			(xy 203.2 123.19) (xy 205.74 123.19)
		)
		(stroke
			(width 0)
			(type default)
		)
	)
	(wire
		(pts
			(xy 232.41 124.46) (xy 232.41 128.27)
		)
		(stroke
			(width 0)
			(type default)
		)
	)
	(bus
		(pts
			(xy 270.51 104.14) (xy 270.51 106.68)
		)
		(stroke
			(width 0)
			(type default)
		)
	)
	(wire
		(pts
			(xy 62.23 203.2) (xy 66.04 203.2)
		)
		(stroke
			(width 0)
			(type default)
		)
	)
	(wire
		(pts
			(xy 144.78 64.77) (xy 151.13 64.77)
		)
		(stroke
			(width 0)
			(type default)
		)
	)
	(wire
		(pts
			(xy 86.36 240.03) (xy 86.36 241.3)
		)
		(stroke
			(width 0)
			(type default)
		)
	)
	(wire
		(pts
			(xy 144.78 60.96) (xy 144.78 64.77)
		)
		(stroke
			(width 0)
			(type default)
		)
	)
	(wire
		(pts
			(xy 144.78 72.39) (xy 144.78 76.2)
		)
		(stroke
			(width 0)
			(type default)
		)
	)
	(wire
		(pts
			(xy 252.73 72.39) (xy 255.27 72.39)
		)
		(stroke
			(width 0)
			(type default)
		)
	)
	(wire
		(pts
			(xy 189.23 91.44) (xy 189.23 87.63)
		)
		(stroke
			(width 0)
			(type default)
		)
	)
	(wire
		(pts
			(xy 189.23 91.44) (xy 205.74 91.44)
		)
		(stroke
			(width 0)
			(type default)
		)
	)
	(wire
		(pts
			(xy 83.82 232.41) (xy 90.17 232.41)
		)
		(stroke
			(width 0)
			(type default)
		)
	)
	(wire
		(pts
			(xy 146.05 119.38) (xy 146.05 121.92)
		)
		(stroke
			(width 0)
			(type default)
		)
	)
	(bus
		(pts
			(xy 270.51 101.6) (xy 270.51 104.14)
		)
		(stroke
			(width 0)
			(type default)
		)
	)
	(wire
		(pts
			(xy 191.77 88.9) (xy 205.74 88.9)
		)
		(stroke
			(width 0)
			(type default)
		)
	)
	(wire
		(pts
			(xy 63.5 199.39) (xy 63.5 200.66)
		)
		(stroke
			(width 0)
			(type default)
		)
	)
	(wire
		(pts
			(xy 242.57 72.39) (xy 245.11 72.39)
		)
		(stroke
			(width 0)
			(type default)
		)
	)
	(wire
		(pts
			(xy 146.05 130.81) (xy 142.24 130.81)
		)
		(stroke
			(width 0)
			(type default)
		)
	)
	(wire
		(pts
			(xy 144.78 64.77) (xy 144.78 67.31)
		)
		(stroke
			(width 0)
			(type default)
		)
	)
	(wire
		(pts
			(xy 232.41 109.22) (xy 267.97 109.22)
		)
		(stroke
			(width 0)
			(type default)
		)
	)
	(bus
		(pts
			(xy 270.51 106.68) (xy 270.51 109.22)
		)
		(stroke
			(width 0)
			(type default)
		)
	)
	(wire
		(pts
			(xy 35.56 238.76) (xy 35.56 240.03)
		)
		(stroke
			(width 0)
			(type default)
		)
	)
	(wire
		(pts
			(xy 83.82 200.66) (xy 85.09 200.66)
		)
		(stroke
			(width 0)
			(type default)
		)
	)
	(polyline
		(pts
			(xy 111.76 240.03) (xy 152.4 240.03)
		)
		(stroke
			(width 0)
			(type default)
		)
	)
	(wire
		(pts
			(xy 85.09 199.39) (xy 85.09 200.66)
		)
		(stroke
			(width 0)
			(type default)
		)
	)
	(wire
		(pts
			(xy 232.41 72.39) (xy 237.49 72.39)
		)
		(stroke
			(width 0)
			(type default)
		)
	)
	(wire
		(pts
			(xy 252.73 82.55) (xy 252.73 91.44)
		)
		(stroke
			(width 0)
			(type default)
		)
	)
	(bus
		(pts
			(xy 185.42 90.17) (xy 186.69 91.44)
		)
		(stroke
			(width 0)
			(type default)
		)
	)
	(wire
		(pts
			(xy 267.97 88.9) (xy 255.27 88.9)
		)
		(stroke
			(width 0)
			(type default)
		)
	)
	(wire
		(pts
			(xy 63.5 200.66) (xy 66.04 200.66)
		)
		(stroke
			(width 0)
			(type default)
		)
	)
	(wire
		(pts
			(xy 240.03 72.39) (xy 240.03 77.47)
		)
		(stroke
			(width 0)
			(type default)
		)
	)
	(wire
		(pts
			(xy 232.41 111.76) (xy 267.97 111.76)
		)
		(stroke
			(width 0)
			(type default)
		)
	)
	(wire
		(pts
			(xy 63.5 231.14) (xy 63.5 232.41)
		)
		(stroke
			(width 0)
			(type default)
		)
	)
	(wire
		(pts
			(xy 242.57 101.6) (xy 267.97 101.6)
		)
		(stroke
			(width 0)
			(type default)
		)
	)
	(wire
		(pts
			(xy 229.87 109.22) (xy 232.41 109.22)
		)
		(stroke
			(width 0)
			(type default)
		)
	)
	(wire
		(pts
			(xy 250.19 72.39) (xy 250.19 77.47)
		)
		(stroke
			(width 0)
			(type default)
		)
	)
	(wire
		(pts
			(xy 128.27 213.36) (xy 133.35 213.36)
		)
		(stroke
			(width 0)
			(type default)
		)
	)
	(wire
		(pts
			(xy 175.26 72.39) (xy 175.26 76.2)
		)
		(stroke
			(width 0)
			(type default)
		)
	)
	(wire
		(pts
			(xy 250.19 72.39) (xy 252.73 72.39)
		)
		(stroke
			(width 0)
			(type default)
		)
	)
	(polyline
		(pts
			(xy 111.76 234.95) (xy 152.4 234.95)
		)
		(stroke
			(width 0)
			(type default)
		)
	)
	(wire
		(pts
			(xy 152.4 127) (xy 152.4 130.81)
		)
		(stroke
			(width 0)
			(type default)
		)
	)
	(wire
		(pts
			(xy 255.27 82.55) (xy 255.27 88.9)
		)
		(stroke
			(width 0)
			(type default)
		)
	)
	(wire
		(pts
			(xy 85.09 193.04) (xy 85.09 194.31)
		)
		(stroke
			(width 0)
			(type default)
		)
	)
	(wire
		(pts
			(xy 229.87 106.68) (xy 237.49 106.68)
		)
		(stroke
			(width 0)
			(type default)
		)
	)
	(wire
		(pts
			(xy 242.57 72.39) (xy 242.57 77.47)
		)
		(stroke
			(width 0)
			(type default)
		)
	)
	(wire
		(pts
			(xy 57.15 214.63) (xy 57.15 215.9)
		)
		(stroke
			(width 0)
			(type default)
		)
	)
	(wire
		(pts
			(xy 237.49 106.68) (xy 267.97 106.68)
		)
		(stroke
			(width 0)
			(type default)
		)
	)
	(wire
		(pts
			(xy 250.19 82.55) (xy 250.19 93.98)
		)
		(stroke
			(width 0)
			(type default)
		)
	)
	(wire
		(pts
			(xy 152.4 119.38) (xy 152.4 121.92)
		)
		(stroke
			(width 0)
			(type default)
		)
	)
	(wire
		(pts
			(xy 158.75 130.81) (xy 165.1 130.81)
		)
		(stroke
			(width 0)
			(type default)
		)
	)
	(wire
		(pts
			(xy 83.82 240.03) (xy 86.36 240.03)
		)
		(stroke
			(width 0)
			(type default)
		)
	)
	(wire
		(pts
			(xy 146.05 119.38) (xy 152.4 119.38)
		)
		(stroke
			(width 0)
			(type default)
		)
	)
	(wire
		(pts
			(xy 54.61 205.74) (xy 57.15 205.74)
		)
		(stroke
			(width 0)
			(type default)
		)
	)
	(wire
		(pts
			(xy 245.11 99.06) (xy 267.97 99.06)
		)
		(stroke
			(width 0)
			(type default)
		)
	)
	(wire
		(pts
			(xy 247.65 82.55) (xy 247.65 96.52)
		)
		(stroke
			(width 0)
			(type default)
		)
	)
	(wire
		(pts
			(xy 250.19 93.98) (xy 267.97 93.98)
		)
		(stroke
			(width 0)
			(type default)
		)
	)
	(wire
		(pts
			(xy 157.48 76.2) (xy 163.83 76.2)
		)
		(stroke
			(width 0)
			(type default)
		)
	)
	(wire
		(pts
			(xy 229.87 101.6) (xy 242.57 101.6)
		)
		(stroke
			(width 0)
			(type default)
		)
	)
	(wire
		(pts
			(xy 229.87 104.14) (xy 240.03 104.14)
		)
		(stroke
			(width 0)
			(type default)
		)
	)
	(bus
		(pts
			(xy 186.69 93.98) (xy 186.69 96.52)
		)
		(stroke
			(width 0)
			(type default)
		)
	)
	(wire
		(pts
			(xy 240.03 72.39) (xy 242.57 72.39)
		)
		(stroke
			(width 0)
			(type default)
		)
	)
	(wire
		(pts
			(xy 247.65 96.52) (xy 267.97 96.52)
		)
		(stroke
			(width 0)
			(type default)
		)
	)
	(wire
		(pts
			(xy 92.71 203.2) (xy 100.33 203.2)
		)
		(stroke
			(width 0)
			(type default)
		)
	)
	(wire
		(pts
			(xy 165.1 119.38) (xy 175.26 119.38)
		)
		(stroke
			(width 0)
			(type default)
		)
	)
	(wire
		(pts
			(xy 163.83 64.77) (xy 163.83 67.31)
		)
		(stroke
			(width 0)
			(type default)
		)
	)
	(wire
		(pts
			(xy 245.11 72.39) (xy 245.11 77.47)
		)
		(stroke
			(width 0)
			(type default)
		)
	)
	(wire
		(pts
			(xy 54.61 187.96) (xy 45.72 187.96)
		)
		(stroke
			(width 0)
			(type default)
		)
	)
	(wire
		(pts
			(xy 163.83 72.39) (xy 163.83 76.2)
		)
		(stroke
			(width 0)
			(type default)
		)
	)
	(polyline
		(pts
			(xy 152.4 234.95) (xy 152.4 240.03)
		)
		(stroke
			(width 0)
			(type default)
		)
	)
	(wire
		(pts
			(xy 62.23 208.28) (xy 66.04 208.28)
		)
		(stroke
			(width 0)
			(type default)
		)
	)
	(bus
		(pts
			(xy 270.51 86.36) (xy 270.51 88.9)
		)
		(stroke
			(width 0)
			(type default)
		)
	)
	(wire
		(pts
			(xy 229.87 96.52) (xy 247.65 96.52)
		)
		(stroke
			(width 0)
			(type default)
		)
	)
	(wire
		(pts
			(xy 142.24 130.81) (xy 142.24 132.08)
		)
		(stroke
			(width 0)
			(type default)
		)
	)
	(wire
		(pts
			(xy 63.5 240.03) (xy 66.04 240.03)
		)
		(stroke
			(width 0)
			(type default)
		)
	)
	(wire
		(pts
			(xy 245.11 72.39) (xy 247.65 72.39)
		)
		(stroke
			(width 0)
			(type default)
		)
	)
	(wire
		(pts
			(xy 232.41 111.76) (xy 232.41 119.38)
		)
		(stroke
			(width 0)
			(type default)
		)
	)
	(wire
		(pts
			(xy 62.23 203.2) (xy 62.23 208.28)
		)
		(stroke
			(width 0)
			(type default)
		)
	)
	(wire
		(pts
			(xy 240.03 104.14) (xy 267.97 104.14)
		)
		(stroke
			(width 0)
			(type default)
		)
	)
	(bus
		(pts
			(xy 270.51 85.09) (xy 270.51 86.36)
		)
		(stroke
			(width 0)
			(type default)
		)
	)
	(wire
		(pts
			(xy 151.13 72.39) (xy 151.13 76.2)
		)
		(stroke
			(width 0)
			(type default)
		)
	)
	(bus
		(pts
			(xy 185.42 90.17) (xy 184.15 90.17)
		)
		(stroke
			(width 0)
			(type default)
		)
	)
	(wire
		(pts
			(xy 242.57 82.55) (xy 242.57 101.6)
		)
		(stroke
			(width 0)
			(type default)
		)
	)
	(wire
		(pts
			(xy 31.75 208.28) (xy 62.23 208.28)
		)
		(stroke
			(width 0)
			(type default)
		)
	)
	(wire
		(pts
			(xy 57.15 205.74) (xy 66.04 205.74)
		)
		(stroke
			(width 0)
			(type default)
		)
	)
	(bus
		(pts
			(xy 270.51 91.44) (xy 270.51 93.98)
		)
		(stroke
			(width 0)
			(type default)
		)
	)
	(wire
		(pts
			(xy 92.71 200.66) (xy 92.71 203.2)
		)
		(stroke
			(width 0)
			(type default)
		)
	)
	(wire
		(pts
			(xy 203.2 62.23) (xy 203.2 74.93)
		)
		(stroke
			(width 0)
			(type default)
		)
	)
	(wire
		(pts
			(xy 157.48 64.77) (xy 157.48 67.31)
		)
		(stroke
			(width 0)
			(type default)
		)
	)
	(wire
		(pts
			(xy 151.13 76.2) (xy 157.48 76.2)
		)
		(stroke
			(width 0)
			(type default)
		)
	)
	(bus
		(pts
			(xy 270.51 99.06) (xy 270.51 101.6)
		)
		(stroke
			(width 0)
			(type default)
		)
	)
	(wire
		(pts
			(xy 189.23 96.52) (xy 205.74 96.52)
		)
		(stroke
			(width 0)
			(type default)
		)
	)
	(bus
		(pts
			(xy 270.51 96.52) (xy 270.51 99.06)
		)
		(stroke
			(width 0)
			(type default)
		)
	)
	(wire
		(pts
			(xy 245.11 82.55) (xy 245.11 99.06)
		)
		(stroke
			(width 0)
			(type default)
		)
	)
	(wire
		(pts
			(xy 63.5 232.41) (xy 66.04 232.41)
		)
		(stroke
			(width 0)
			(type default)
		)
	)
	(wire
		(pts
			(xy 229.87 88.9) (xy 255.27 88.9)
		)
		(stroke
			(width 0)
			(type default)
		)
	)
	(label "SD_VDD"
		(at 85.09 193.04 90)
		(effects
			(font
				(size 1.27 1.27)
			)
			(justify left bottom)
		)
	)
	(label "SD_VDD"
		(at 175.26 119.38 180)
		(effects
			(font
				(size 1.27 1.27)
			)
			(justify right bottom)
		)
	)
	(label "EMMC.CLK"
		(at 189.865 96.52 0)
		(effects
			(font
				(size 1.27 1.27)
			)
			(justify left bottom)
		)
	)
	(label "EMMC.DAT1"
		(at 267.97 91.44 180)
		(effects
			(font
				(size 1.27 1.27)
			)
			(justify right bottom)
		)
	)
	(label "SD_VDD"
		(at 128.27 198.12 270)
		(effects
			(font
				(size 1.27 1.27)
			)
			(justify right bottom)
		)
	)
	(label "SD_VDD"
		(at 191.77 93.98 0)
		(effects
			(font
				(size 1.27 1.27)
			)
			(justify left bottom)
		)
	)
	(label "EMMC.RST_n"
		(at 189.865 99.06 0)
		(effects
			(font
				(size 1.27 1.27)
			)
			(justify left bottom)
		)
	)
	(label "SD_VDD"
		(at 232.41 62.23 270)
		(effects
			(font
				(size 1.27 1.27)
			)
			(justify right bottom)
		)
	)
	(label "EMMC.DAT0"
		(at 267.97 88.9 180)
		(effects
			(font
				(size 1.27 1.27)
			)
			(justify right bottom)
		)
	)
	(label "EMMC.DAT4"
		(at 267.97 99.06 180)
		(effects
			(font
				(size 1.27 1.27)
			)
			(justify right bottom)
		)
	)
	(label "SD_VDD"
		(at 54.61 187.96 180)
		(effects
			(font
				(size 1.27 1.27)
			)
			(justify right bottom)
		)
	)
	(label "EMMC.DAT6"
		(at 267.97 104.14 180)
		(effects
			(font
				(size 1.27 1.27)
			)
			(justify right bottom)
		)
	)
	(label "SD_VDD"
		(at 203.2 62.23 270)
		(effects
			(font
				(size 1.27 1.27)
			)
			(justify right bottom)
		)
	)
	(label "EMMC.DAT7"
		(at 267.97 106.68 180)
		(effects
			(font
				(size 1.27 1.27)
			)
			(justify right bottom)
		)
	)
	(label "EMMC.CMD"
		(at 267.97 109.22 180)
		(effects
			(font
				(size 1.27 1.27)
			)
			(justify right bottom)
		)
	)
	(label "EMMC.DAT2"
		(at 267.97 93.98 180)
		(effects
			(font
				(size 1.27 1.27)
			)
			(justify right bottom)
		)
	)
	(label "eMMC_VDDI"
		(at 175.26 53.34 270)
		(effects
			(font
				(size 1.27 1.27)
			)
			(justify right bottom)
		)
	)
	(label "EMMC.DAT5"
		(at 267.97 101.6 180)
		(effects
			(font
				(size 1.27 1.27)
			)
			(justify right bottom)
		)
	)
	(label "eMMC_VDDI"
		(at 191.77 88.9 0)
		(effects
			(font
				(size 1.27 1.27)
			)
			(justify left bottom)
		)
	)
	(label "EMMC.DAT3"
		(at 267.97 96.52 180)
		(effects
			(font
				(size 1.27 1.27)
			)
			(justify right bottom)
		)
	)
	(label "EMMC.STRB"
		(at 267.97 111.76 180)
		(effects
			(font
				(size 1.27 1.27)
			)
			(justify right bottom)
		)
	)
	(global_label "SD_VDD_OVERRIDE"
		(shape input)
		(at 58.42 237.49 180)
		(effects
			(font
				(size 1.27 1.27)
			)
			(justify right)
		)
		(property "Intersheetrefs" "${INTERSHEET_REFS}"
			(at 58.42 234.315 0)
			(effects
				(font
					(size 1.27 1.27)
				)
				(justify right)
			)
		)
	)
	(global_label "SD_VDD_OVERRIDE"
		(shape input)
		(at 54.61 205.74 180)
		(effects
			(font
				(size 1.27 1.27)
			)
			(justify right)
		)
		(property "Intersheetrefs" "${INTERSHEET_REFS}"
			(at 54.61 202.565 0)
			(effects
				(font
					(size 1.27 1.27)
				)
				(justify right)
			)
		)
	)
	(global_label "SD_VDD_FLAG"
		(shape output)
		(at 100.33 203.2 0)
		(fields_autoplaced yes)
		(effects
			(font
				(size 1.27 1.27)
			)
			(justify left)
		)
		(property "Intersheetrefs" "${INTERSHEET_REFS}"
			(at 115.8338 203.2 0)
			(effects
				(font
					(size 1.27 1.27)
				)
				(justify left)
			)
		)
	)
	(global_label "SD_PWR_ON"
		(shape input)
		(at 133.35 213.36 0)
		(fields_autoplaced yes)
		(effects
			(font
				(size 1.27 1.27)
			)
			(justify left)
		)
		(property "Intersheetrefs" "${INTERSHEET_REFS}"
			(at 146.8302 213.2806 0)
			(effects
				(font
					(size 1.27 1.27)
				)
				(justify left)
			)
		)
	)
	(global_label "SD_VDD_AUX"
		(shape output)
		(at 100.33 232.41 0)
		(fields_autoplaced yes)
		(effects
			(font
				(size 1.27 1.27)
			)
			(justify left)
		)
		(property "Intersheetrefs" "${INTERSHEET_REFS}"
			(at 114.9871 232.41 0)
			(effects
				(font
					(size 1.27 1.27)
				)
				(justify left)
			)
		)
	)
	(global_label "SD_VDD"
		(shape input)
		(at 45.72 187.96 180)
		(fields_autoplaced yes)
		(effects
			(font
				(size 1.27 1.27)
			)
			(justify right)
		)
		(property "Intersheetrefs" "${INTERSHEET_REFS}"
			(at 35.6591 187.96 0)
			(effects
				(font
					(size 1.27 1.27)
				)
				(justify right)
			)
		)
	)
	(hierarchical_label "EMMC{SDIO}"
		(shape input)
		(at 184.15 90.17 180)
		(effects
			(font
				(size 1.27 1.27)
			)
			(justify right)
		)
	)
	(hierarchical_label "EMMC{SDIO}"
		(shape input)
		(at 273.05 83.82 0)
		(effects
			(font
				(size 1.27 1.27)
			)
			(justify left)
		)
	)
	(symbol
		(lib_id "antmicroResistors0402:R_49k9_0402")
		(at 240.03 82.55 90)
		(unit 1)
		(exclude_from_sim no)
		(in_bom yes)
		(on_board yes)
		(dnp no)
		(property "Reference" "R32"
			(at 238.76 73.66 0)
			(effects
				(font
					(size 1.27 1.27)
					(thickness 0.15)
				)
				(justify right)
			)
		)
		(property "Value" "R_49k9_0402"
			(at 252.73 62.23 0)
			(effects
				(font
					(size 1.27 1.27)
					(thickness 0.15)
				)
				(justify left bottom)
				(hide yes)
			)
		)
		(property "Footprint" "antmicro-footprints:R_0402_1005Metric"
			(at 255.27 62.23 0)
			(effects
				(font
					(size 1.27 1.27)
					(thickness 0.15)
				)
				(justify left bottom)
				(hide yes)
			)
		)
		(property "Datasheet" "https://www.bourns.com/docs/product-datasheets/cr.pdf"
			(at 257.81 62.23 0)
			(effects
				(font
					(size 1.27 1.27)
					(thickness 0.15)
				)
				(justify left bottom)
				(hide yes)
			)
		)
		(property "Description" "SMD Chip Resistor, 49.9 kohm, ± 1%, 63 mW, 0402 [1005 Metric], Thick Film, General Purpose"
			(at 240.03 82.55 0)
			(effects
				(font
					(size 1.27 1.27)
				)
				(hide yes)
			)
		)
		(property "MPN" "CR0402-FX-4992GLF"
			(at 260.35 62.23 0)
			(effects
				(font
					(size 1.27 1.27)
					(thickness 0.15)
				)
				(justify left bottom)
				(hide yes)
			)
		)
		(property "Manufacturer" "Bourns"
			(at 262.89 62.23 0)
			(effects
				(font
					(size 1.27 1.27)
					(thickness 0.15)
				)
				(justify left bottom)
				(hide yes)
			)
		)
		(property "License" "Apache-2.0"
			(at 265.43 62.23 0)
			(effects
				(font
					(size 1.27 1.27)
					(thickness 0.15)
				)
				(justify left bottom)
				(hide yes)
			)
		)
		(property "Author" "Antmicro"
			(at 267.97 62.23 0)
			(effects
				(font
					(size 1.27 1.27)
					(thickness 0.15)
				)
				(justify left bottom)
				(hide yes)
			)
		)
		(property "Val" "49k9"
			(at 238.76 82.55 0)
			(effects
				(font
					(size 1.27 1.27)
					(thickness 0.15)
				)
				(justify right)
			)
		)
		(property "Tolerance" "1%"
			(at 250.19 62.23 0)
			(effects
				(font
					(size 1.27 1.27)
				)
				(justify left bottom)
				(hide yes)
			)
		)
		(property "Public" ""
			(at 270.51 62.23 0)
			(effects
				(font
					(size 1.27 1.27)
				)
				(justify left bottom)
				(hide yes)
			)
		)
		(pin "1"
		)
		(pin "2"
		)
		(instances
			(project "polarfire-som"
				(path ""
					(reference "R32")
					(unit 1)
				)
			)
		)
	)
	(symbol
		(lib_id "antmicropower:GND")
		(at 140.97 76.2 0)
		(unit 1)
		(exclude_from_sim no)
		(in_bom yes)
		(on_board yes)
		(dnp no)
		(fields_autoplaced yes)
		(property "Reference" "#PWR046"
			(at 149.86 78.74 0)
			(effects
				(font
					(size 1.27 1.27)
					(thickness 0.15)
				)
				(justify left bottom)
				(hide yes)
			)
		)
		(property "Value" "GND"
			(at 140.97 81.28 0)
			(effects
				(font
					(size 1.27 1.27)
					(thickness 0.15)
				)
			)
		)
		(property "Footprint" ""
			(at 149.86 83.82 0)
			(effects
				(font
					(size 1.27 1.27)
					(thickness 0.15)
				)
				(justify left bottom)
				(hide yes)
			)
		)
		(property "Datasheet" ""
			(at 149.86 88.9 0)
			(effects
				(font
					(size 1.27 1.27)
					(thickness 0.15)
				)
				(justify left bottom)
				(hide yes)
			)
		)
		(property "Description" ""
			(at 140.97 76.2 0)
			(effects
				(font
					(size 1.27 1.27)
				)
				(hide yes)
			)
		)
		(property "Author" "Antmicro"
			(at 149.86 83.82 0)
			(effects
				(font
					(size 1.27 1.27)
					(thickness 0.15)
				)
				(justify left bottom)
				(hide yes)
			)
		)
		(property "License" "Apache-2.0"
			(at 149.86 86.36 0)
			(effects
				(font
					(size 1.27 1.27)
					(thickness 0.15)
				)
				(justify left bottom)
				(hide yes)
			)
		)
		(pin "1"
		)
		(instances
			(project "polarfire-som"
				(path ""
					(reference "#PWR046")
					(unit 1)
				)
			)
		)
	)
	(symbol
		(lib_id "antmicroResistors0402:R_49k9_0402")
		(at 250.19 82.55 90)
		(unit 1)
		(exclude_from_sim no)
		(in_bom yes)
		(on_board yes)
		(dnp no)
		(property "Reference" "R36"
			(at 248.92 73.66 0)
			(effects
				(font
					(size 1.27 1.27)
					(thickness 0.15)
				)
				(justify right)
			)
		)
		(property "Value" "R_49k9_0402"
			(at 262.89 62.23 0)
			(effects
				(font
					(size 1.27 1.27)
					(thickness 0.15)
				)
				(justify left bottom)
				(hide yes)
			)
		)
		(property "Footprint" "antmicro-footprints:R_0402_1005Metric"
			(at 265.43 62.23 0)
			(effects
				(font
					(size 1.27 1.27)
					(thickness 0.15)
				)
				(justify left bottom)
				(hide yes)
			)
		)
		(property "Datasheet" "https://www.bourns.com/docs/product-datasheets/cr.pdf"
			(at 267.97 62.23 0)
			(effects
				(font
					(size 1.27 1.27)
					(thickness 0.15)
				)
				(justify left bottom)
				(hide yes)
			)
		)
		(property "Description" "SMD Chip Resistor, 49.9 kohm, ± 1%, 63 mW, 0402 [1005 Metric], Thick Film, General Purpose"
			(at 250.19 82.55 0)
			(effects
				(font
					(size 1.27 1.27)
				)
				(hide yes)
			)
		)
		(property "MPN" "CR0402-FX-4992GLF"
			(at 270.51 62.23 0)
			(effects
				(font
					(size 1.27 1.27)
					(thickness 0.15)
				)
				(justify left bottom)
				(hide yes)
			)
		)
		(property "Manufacturer" "Bourns"
			(at 273.05 62.23 0)
			(effects
				(font
					(size 1.27 1.27)
					(thickness 0.15)
				)
				(justify left bottom)
				(hide yes)
			)
		)
		(property "License" "Apache-2.0"
			(at 275.59 62.23 0)
			(effects
				(font
					(size 1.27 1.27)
					(thickness 0.15)
				)
				(justify left bottom)
				(hide yes)
			)
		)
		(property "Author" "Antmicro"
			(at 278.13 62.23 0)
			(effects
				(font
					(size 1.27 1.27)
					(thickness 0.15)
				)
				(justify left bottom)
				(hide yes)
			)
		)
		(property "Val" "49k9"
			(at 248.92 82.55 0)
			(effects
				(font
					(size 1.27 1.27)
					(thickness 0.15)
				)
				(justify right)
			)
		)
		(property "Tolerance" "1%"
			(at 260.35 62.23 0)
			(effects
				(font
					(size 1.27 1.27)
				)
				(justify left bottom)
				(hide yes)
			)
		)
		(property "Public" ""
			(at 280.67 62.23 0)
			(effects
				(font
					(size 1.27 1.27)
				)
				(justify left bottom)
				(hide yes)
			)
		)
		(pin "1"
		)
		(pin "2"
		)
		(instances
			(project "polarfire-som"
				(path ""
					(reference "R36")
					(unit 1)
				)
			)
		)
	)
	(symbol
		(lib_id "antmicroResistors0402:R_10k_0402")
		(at 232.41 124.46 90)
		(unit 1)
		(exclude_from_sim no)
		(in_bom yes)
		(on_board yes)
		(dnp no)
		(fields_autoplaced yes)
		(property "Reference" "R30"
			(at 234.95 120.6499 90)
			(effects
				(font
					(size 1.27 1.27)
					(thickness 0.15)
				)
				(justify right)
			)
		)
		(property "Value" "R_10k_0402"
			(at 245.11 104.14 0)
			(effects
				(font
					(size 1.27 1.27)
					(thickness 0.15)
				)
				(justify left bottom)
				(hide yes)
			)
		)
		(property "Footprint" "antmicro-footprints:R_0402_1005Metric"
			(at 247.65 104.14 0)
			(effects
				(font
					(size 1.27 1.27)
					(thickness 0.15)
				)
				(justify left bottom)
				(hide yes)
			)
		)
		(property "Datasheet" "https://www.bourns.com/docs/product-datasheets/cr.pdf"
			(at 250.19 104.14 0)
			(effects
				(font
					(size 1.27 1.27)
					(thickness 0.15)
				)
				(justify left bottom)
				(hide yes)
			)
		)
		(property "Description" "SMD Chip Resistor, 10 kohm, ± 1%, 62.5 mW, 0402 [1005 Metric], Thick Film, General Purpose"
			(at 232.41 124.46 0)
			(effects
				(font
					(size 1.27 1.27)
				)
				(hide yes)
			)
		)
		(property "MPN" "CR0402-FX-1002GLF"
			(at 252.73 104.14 0)
			(effects
				(font
					(size 1.27 1.27)
					(thickness 0.15)
				)
				(justify left bottom)
				(hide yes)
			)
		)
		(property "Manufacturer" "Bourns"
			(at 255.27 104.14 0)
			(effects
				(font
					(size 1.27 1.27)
					(thickness 0.15)
				)
				(justify left bottom)
				(hide yes)
			)
		)
		(property "License" "Apache-2.0"
			(at 257.81 104.14 0)
			(effects
				(font
					(size 1.27 1.27)
					(thickness 0.15)
				)
				(justify left bottom)
				(hide yes)
			)
		)
		(property "Author" "Antmicro"
			(at 260.35 104.14 0)
			(effects
				(font
					(size 1.27 1.27)
					(thickness 0.15)
				)
				(justify left bottom)
				(hide yes)
			)
		)
		(property "Val" "10k"
			(at 234.95 123.1899 90)
			(effects
				(font
					(size 1.27 1.27)
					(thickness 0.15)
				)
				(justify right)
			)
		)
		(property "Tolerance" "1%"
			(at 242.57 104.14 0)
			(effects
				(font
					(size 1.27 1.27)
				)
				(justify left bottom)
				(hide yes)
			)
		)
		(property "Public" ""
			(at 262.89 104.14 0)
			(effects
				(font
					(size 1.27 1.27)
				)
				(justify left bottom)
				(hide yes)
			)
		)
		(pin "1"
		)
		(pin "2"
		)
		(instances
			(project "polarfire-som"
				(path ""
					(reference "R30")
					(unit 1)
				)
			)
		)
	)
	(symbol
		(lib_id "antmicroCapacitors0402:C_10u_0402")
		(at 144.78 72.39 90)
		(unit 1)
		(exclude_from_sim no)
		(in_bom yes)
		(on_board yes)
		(dnp no)
		(property "Reference" "C69"
			(at 144.78 67.31 90)
			(effects
				(font
					(size 1.27 1.27)
					(thickness 0.15)
				)
				(justify right)
			)
		)
		(property "Value" "C_10u_0402"
			(at 154.94 52.07 0)
			(effects
				(font
					(size 1.27 1.27)
					(thickness 0.15)
				)
				(justify left bottom)
				(hide yes)
			)
		)
		(property "Footprint" "antmicro-footprints:C_0402_1005Metric"
			(at 157.48 52.07 0)
			(effects
				(font
					(size 1.27 1.27)
					(thickness 0.15)
				)
				(justify left bottom)
				(hide yes)
			)
		)
		(property "Datasheet" "https://www.yageo.com/en/Chart/Download/pdf/CC0402MRX5R5BB106"
			(at 160.02 52.07 0)
			(effects
				(font
					(size 1.27 1.27)
					(thickness 0.15)
				)
				(justify left bottom)
				(hide yes)
			)
		)
		(property "Description" "SMD Multilayer Ceramic Capacitor, 10 µF, 6.3 V, 0402 [1005 Metric], ± 20%, X5R, CC Series"
			(at 144.78 72.39 0)
			(effects
				(font
					(size 1.27 1.27)
				)
				(hide yes)
			)
		)
		(property "MPN" "CC0402MRX5R5BB106"
			(at 162.56 52.07 0)
			(effects
				(font
					(size 1.27 1.27)
					(thickness 0.15)
				)
				(justify left bottom)
				(hide yes)
			)
		)
		(property "Manufacturer" "YAGEO"
			(at 165.1 52.07 0)
			(effects
				(font
					(size 1.27 1.27)
					(thickness 0.15)
				)
				(justify left bottom)
				(hide yes)
			)
		)
		(property "License" "Apache-2.0"
			(at 167.64 52.07 0)
			(effects
				(font
					(size 1.27 1.27)
					(thickness 0.15)
				)
				(justify left bottom)
				(hide yes)
			)
		)
		(property "Author" "Antmicro"
			(at 170.18 52.07 0)
			(effects
				(font
					(size 1.27 1.27)
					(thickness 0.15)
				)
				(justify left bottom)
				(hide yes)
			)
		)
		(property "Val" "10u"
			(at 144.78 72.39 90)
			(effects
				(font
					(size 1.27 1.27)
					(thickness 0.15)
				)
				(justify right)
			)
		)
		(property "Voltage" ""
			(at 172.72 52.07 0)
			(effects
				(font
					(size 1.27 1.27)
				)
				(justify left bottom)
				(hide yes)
			)
		)
		(property "Dielectric" ""
			(at 175.26 52.07 0)
			(effects
				(font
					(size 1.27 1.27)
				)
				(justify left bottom)
				(hide yes)
			)
		)
		(property "Public" ""
			(at 177.8 52.07 0)
			(effects
				(font
					(size 1.27 1.27)
				)
				(justify left bottom)
				(hide yes)
			)
		)
		(pin "1"
		)
		(pin "2"
		)
		(instances
			(project "polarfire-som"
				(path ""
					(reference "C69")
					(unit 1)
				)
			)
		)
	)
	(symbol
		(lib_id "antmicropower:GND")
		(at 232.41 128.27 0)
		(unit 1)
		(exclude_from_sim no)
		(in_bom yes)
		(on_board yes)
		(dnp no)
		(fields_autoplaced yes)
		(property "Reference" "#PWR052"
			(at 241.3 130.81 0)
			(effects
				(font
					(size 1.27 1.27)
					(thickness 0.15)
				)
				(justify left bottom)
				(hide yes)
			)
		)
		(property "Value" "GND"
			(at 232.41 133.35 0)
			(effects
				(font
					(size 1.27 1.27)
					(thickness 0.15)
				)
			)
		)
		(property "Footprint" ""
			(at 241.3 135.89 0)
			(effects
				(font
					(size 1.27 1.27)
					(thickness 0.15)
				)
				(justify left bottom)
				(hide yes)
			)
		)
		(property "Datasheet" ""
			(at 241.3 140.97 0)
			(effects
				(font
					(size 1.27 1.27)
					(thickness 0.15)
				)
				(justify left bottom)
				(hide yes)
			)
		)
		(property "Description" ""
			(at 232.41 128.27 0)
			(effects
				(font
					(size 1.27 1.27)
				)
				(hide yes)
			)
		)
		(property "Author" "Antmicro"
			(at 241.3 135.89 0)
			(effects
				(font
					(size 1.27 1.27)
					(thickness 0.15)
				)
				(justify left bottom)
				(hide yes)
			)
		)
		(property "License" "Apache-2.0"
			(at 241.3 138.43 0)
			(effects
				(font
					(size 1.27 1.27)
					(thickness 0.15)
				)
				(justify left bottom)
				(hide yes)
			)
		)
		(pin "1"
		)
		(instances
			(project "polarfire-som"
				(path ""
					(reference "#PWR052")
					(unit 1)
				)
			)
		)
	)
	(symbol
		(lib_id "antmicroResistors0402:R_10k_0402")
		(at 232.41 82.55 270)
		(mirror x)
		(unit 1)
		(exclude_from_sim no)
		(in_bom yes)
		(on_board yes)
		(dnp no)
		(property "Reference" "R29"
			(at 233.68 77.47 0)
			(effects
				(font
					(size 1.27 1.27)
					(thickness 0.15)
				)
				(justify left)
			)
		)
		(property "Value" "R_10k_0402"
			(at 219.71 62.23 0)
			(effects
				(font
					(size 1.27 1.27)
					(thickness 0.15)
				)
				(justify left bottom)
				(hide yes)
			)
		)
		(property "Footprint" "antmicro-footprints:R_0402_1005Metric"
			(at 217.17 62.23 0)
			(effects
				(font
					(size 1.27 1.27)
					(thickness 0.15)
				)
				(justify left bottom)
				(hide yes)
			)
		)
		(property "Datasheet" "https://www.bourns.com/docs/product-datasheets/cr.pdf"
			(at 214.63 62.23 0)
			(effects
				(font
					(size 1.27 1.27)
					(thickness 0.15)
				)
				(justify left bottom)
				(hide yes)
			)
		)
		(property "Description" "SMD Chip Resistor, 10 kohm, ± 1%, 62.5 mW, 0402 [1005 Metric], Thick Film, General Purpose"
			(at 232.41 82.55 0)
			(effects
				(font
					(size 1.27 1.27)
				)
				(hide yes)
			)
		)
		(property "MPN" "CR0402-FX-1002GLF"
			(at 212.09 62.23 0)
			(effects
				(font
					(size 1.27 1.27)
					(thickness 0.15)
				)
				(justify left bottom)
				(hide yes)
			)
		)
		(property "Manufacturer" "Bourns"
			(at 209.55 62.23 0)
			(effects
				(font
					(size 1.27 1.27)
					(thickness 0.15)
				)
				(justify left bottom)
				(hide yes)
			)
		)
		(property "License" "Apache-2.0"
			(at 207.01 62.23 0)
			(effects
				(font
					(size 1.27 1.27)
					(thickness 0.15)
				)
				(justify left bottom)
				(hide yes)
			)
		)
		(property "Author" "Antmicro"
			(at 204.47 62.23 0)
			(effects
				(font
					(size 1.27 1.27)
					(thickness 0.15)
				)
				(justify left bottom)
				(hide yes)
			)
		)
		(property "Val" "10k"
			(at 233.68 82.55 0)
			(effects
				(font
					(size 1.27 1.27)
					(thickness 0.15)
				)
				(justify right)
			)
		)
		(property "Tolerance" "1%"
			(at 222.25 62.23 0)
			(effects
				(font
					(size 1.27 1.27)
				)
				(justify left bottom)
				(hide yes)
			)
		)
		(property "Public" ""
			(at 201.93 62.23 0)
			(effects
				(font
					(size 1.27 1.27)
				)
				(justify left bottom)
				(hide yes)
			)
		)
		(pin "1"
		)
		(pin "2"
		)
		(instances
			(project "polarfire-som"
				(path ""
					(reference "R29")
					(unit 1)
				)
			)
		)
	)
	(symbol
		(lib_id "antmicropower:GND")
		(at 203.2 127 0)
		(unit 1)
		(exclude_from_sim no)
		(in_bom yes)
		(on_board yes)
		(dnp no)
		(fields_autoplaced yes)
		(property "Reference" "#PWR050"
			(at 212.09 129.54 0)
			(effects
				(font
					(size 1.27 1.27)
					(thickness 0.15)
				)
				(justify left bottom)
				(hide yes)
			)
		)
		(property "Value" "GND"
			(at 203.2 132.08 0)
			(effects
				(font
					(size 1.27 1.27)
					(thickness 0.15)
				)
			)
		)
		(property "Footprint" ""
			(at 212.09 134.62 0)
			(effects
				(font
					(size 1.27 1.27)
					(thickness 0.15)
				)
				(justify left bottom)
				(hide yes)
			)
		)
		(property "Datasheet" ""
			(at 212.09 139.7 0)
			(effects
				(font
					(size 1.27 1.27)
					(thickness 0.15)
				)
				(justify left bottom)
				(hide yes)
			)
		)
		(property "Description" ""
			(at 203.2 127 0)
			(effects
				(font
					(size 1.27 1.27)
				)
				(hide yes)
			)
		)
		(property "Author" "Antmicro"
			(at 212.09 134.62 0)
			(effects
				(font
					(size 1.27 1.27)
					(thickness 0.15)
				)
				(justify left bottom)
				(hide yes)
			)
		)
		(property "License" "Apache-2.0"
			(at 212.09 137.16 0)
			(effects
				(font
					(size 1.27 1.27)
					(thickness 0.15)
				)
				(justify left bottom)
				(hide yes)
			)
		)
		(pin "1"
		)
		(instances
			(project "polarfire-som"
				(path ""
					(reference "#PWR050")
					(unit 1)
				)
			)
		)
	)
	(symbol
		(lib_id "antmicropower:+3V3")
		(at 144.78 60.96 0)
		(unit 1)
		(exclude_from_sim no)
		(in_bom yes)
		(on_board yes)
		(dnp no)
		(fields_autoplaced yes)
		(property "Reference" "#PWR048"
			(at 160.02 63.5 0)
			(effects
				(font
					(size 1.27 1.27)
					(thickness 0.15)
				)
				(justify left bottom)
				(hide yes)
			)
		)
		(property "Value" "+3V3"
			(at 144.78 55.88 0)
			(effects
				(font
					(size 1.27 1.27)
					(thickness 0.15)
				)
			)
		)
		(property "Footprint" ""
			(at 160.02 68.58 0)
			(effects
				(font
					(size 1.27 1.27)
					(thickness 0.15)
				)
				(justify left bottom)
				(hide yes)
			)
		)
		(property "Datasheet" ""
			(at 160.02 71.12 0)
			(effects
				(font
					(size 1.27 1.27)
					(thickness 0.15)
				)
				(justify left bottom)
				(hide yes)
			)
		)
		(property "Description" ""
			(at 144.78 60.96 0)
			(effects
				(font
					(size 1.27 1.27)
				)
				(hide yes)
			)
		)
		(property "Author" "Antmicro"
			(at 160.02 68.58 0)
			(effects
				(font
					(size 1.27 1.27)
					(thickness 0.15)
				)
				(justify left bottom)
				(hide yes)
			)
		)
		(property "License" "Apache-2.0"
			(at 160.02 71.12 0)
			(effects
				(font
					(size 1.27 1.27)
					(thickness 0.15)
				)
				(justify left bottom)
				(hide yes)
			)
		)
		(pin "1"
		)
		(instances
			(project "polarfire-som"
				(path ""
					(reference "#PWR048")
					(unit 1)
				)
			)
		)
	)
	(symbol
		(lib_id "antmicroResistors0402:R_10k_0402")
		(at 128.27 212.09 90)
		(unit 1)
		(exclude_from_sim no)
		(in_bom yes)
		(on_board yes)
		(dnp no)
		(fields_autoplaced yes)
		(property "Reference" "R54"
			(at 130.175 208.2799 90)
			(effects
				(font
					(size 1.27 1.27)
					(thickness 0.15)
				)
				(justify right)
			)
		)
		(property "Value" "R_10k_0402"
			(at 140.97 191.77 0)
			(effects
				(font
					(size 1.27 1.27)
					(thickness 0.15)
				)
				(justify left bottom)
				(hide yes)
			)
		)
		(property "Footprint" "antmicro-footprints:R_0402_1005Metric"
			(at 143.51 191.77 0)
			(effects
				(font
					(size 1.27 1.27)
					(thickness 0.15)
				)
				(justify left bottom)
				(hide yes)
			)
		)
		(property "Datasheet" "https://www.bourns.com/docs/product-datasheets/cr.pdf"
			(at 146.05 191.77 0)
			(effects
				(font
					(size 1.27 1.27)
					(thickness 0.15)
				)
				(justify left bottom)
				(hide yes)
			)
		)
		(property "Description" "SMD Chip Resistor, 10 kohm, ± 1%, 62.5 mW, 0402 [1005 Metric], Thick Film, General Purpose"
			(at 128.27 212.09 0)
			(effects
				(font
					(size 1.27 1.27)
				)
				(hide yes)
			)
		)
		(property "MPN" "CR0402-FX-1002GLF"
			(at 148.59 191.77 0)
			(effects
				(font
					(size 1.27 1.27)
					(thickness 0.15)
				)
				(justify left bottom)
				(hide yes)
			)
		)
		(property "Manufacturer" "Bourns"
			(at 151.13 191.77 0)
			(effects
				(font
					(size 1.27 1.27)
					(thickness 0.15)
				)
				(justify left bottom)
				(hide yes)
			)
		)
		(property "License" "Apache-2.0"
			(at 153.67 191.77 0)
			(effects
				(font
					(size 1.27 1.27)
					(thickness 0.15)
				)
				(justify left bottom)
				(hide yes)
			)
		)
		(property "Author" "Antmicro"
			(at 156.21 191.77 0)
			(effects
				(font
					(size 1.27 1.27)
					(thickness 0.15)
				)
				(justify left bottom)
				(hide yes)
			)
		)
		(property "Val" "10k"
			(at 130.175 210.8199 90)
			(effects
				(font
					(size 1.27 1.27)
					(thickness 0.15)
				)
				(justify right)
			)
		)
		(property "Tolerance" "1%"
			(at 138.43 191.77 0)
			(effects
				(font
					(size 1.27 1.27)
				)
				(justify left bottom)
				(hide yes)
			)
		)
		(property "Public" ""
			(at 158.75 191.77 0)
			(effects
				(font
					(size 1.27 1.27)
				)
				(justify left bottom)
				(hide yes)
			)
		)
		(pin "1"
		)
		(pin "2"
		)
		(instances
			(project "polarfire-som"
				(path ""
					(reference "R54")
					(unit 1)
				)
			)
		)
	)
	(symbol
		(lib_id "antmicroCapacitors0402:C_100n_0402")
		(at 152.4 127 90)
		(unit 1)
		(exclude_from_sim no)
		(in_bom yes)
		(on_board yes)
		(dnp no)
		(property "Reference" "C79"
			(at 152.4 121.92 90)
			(effects
				(font
					(size 1.27 1.27)
					(thickness 0.15)
				)
				(justify right)
			)
		)
		(property "Value" "C_100n_0402"
			(at 162.56 106.68 0)
			(effects
				(font
					(size 1.27 1.27)
					(thickness 0.15)
				)
				(justify left bottom)
				(hide yes)
			)
		)
		(property "Footprint" "antmicro-footprints:C_0402_1005Metric"
			(at 165.1 106.68 0)
			(effects
				(font
					(size 1.27 1.27)
					(thickness 0.15)
				)
				(justify left bottom)
				(hide yes)
			)
		)
		(property "Datasheet" "https://www.murata.com/products/productdetail?partno=GRM155R61H104KE14%23"
			(at 167.64 106.68 0)
			(effects
				(font
					(size 1.27 1.27)
					(thickness 0.15)
				)
				(justify left bottom)
				(hide yes)
			)
		)
		(property "Description" "SMD Multilayer Ceramic Capacitor, 0.1 µF, 50 V, 0402 [1005 Metric], ± 10%, X5R, GRM Series"
			(at 152.4 127 0)
			(effects
				(font
					(size 1.27 1.27)
				)
				(hide yes)
			)
		)
		(property "MPN" "GRM155R61H104KE14D"
			(at 170.18 106.68 0)
			(effects
				(font
					(size 1.27 1.27)
					(thickness 0.15)
				)
				(justify left bottom)
				(hide yes)
			)
		)
		(property "Manufacturer" "Murata"
			(at 172.72 106.68 0)
			(effects
				(font
					(size 1.27 1.27)
					(thickness 0.15)
				)
				(justify left bottom)
				(hide yes)
			)
		)
		(property "License" "Apache-2.0"
			(at 175.26 106.68 0)
			(effects
				(font
					(size 1.27 1.27)
					(thickness 0.15)
				)
				(justify left bottom)
				(hide yes)
			)
		)
		(property "Author" "Antmicro"
			(at 177.8 106.68 0)
			(effects
				(font
					(size 1.27 1.27)
					(thickness 0.15)
				)
				(justify left bottom)
				(hide yes)
			)
		)
		(property "Val" "100n"
			(at 152.4 127 90)
			(effects
				(font
					(size 1.27 1.27)
					(thickness 0.15)
				)
				(justify right)
			)
		)
		(property "Voltage" "50V"
			(at 180.34 106.68 0)
			(effects
				(font
					(size 1.27 1.27)
				)
				(justify left bottom)
				(hide yes)
			)
		)
		(property "Dielectric" "X5R"
			(at 182.88 106.68 0)
			(effects
				(font
					(size 1.27 1.27)
				)
				(justify left bottom)
				(hide yes)
			)
		)
		(property "Public" ""
			(at 185.42 106.68 0)
			(effects
				(font
					(size 1.27 1.27)
				)
				(justify left bottom)
				(hide yes)
			)
		)
		(pin "1"
		)
		(pin "2"
		)
		(instances
			(project "polarfire-som"
				(path ""
					(reference "C79")
					(unit 1)
				)
			)
		)
	)
	(symbol
		(lib_id "antmicroResistors0402:R_49k9_0402")
		(at 255.27 82.55 90)
		(unit 1)
		(exclude_from_sim no)
		(in_bom yes)
		(on_board yes)
		(dnp no)
		(property "Reference" "R38"
			(at 254 73.66 0)
			(effects
				(font
					(size 1.27 1.27)
					(thickness 0.15)
				)
				(justify right)
			)
		)
		(property "Value" "R_49k9_0402"
			(at 267.97 62.23 0)
			(effects
				(font
					(size 1.27 1.27)
					(thickness 0.15)
				)
				(justify left bottom)
				(hide yes)
			)
		)
		(property "Footprint" "antmicro-footprints:R_0402_1005Metric"
			(at 270.51 62.23 0)
			(effects
				(font
					(size 1.27 1.27)
					(thickness 0.15)
				)
				(justify left bottom)
				(hide yes)
			)
		)
		(property "Datasheet" "https://www.bourns.com/docs/product-datasheets/cr.pdf"
			(at 273.05 62.23 0)
			(effects
				(font
					(size 1.27 1.27)
					(thickness 0.15)
				)
				(justify left bottom)
				(hide yes)
			)
		)
		(property "Description" "SMD Chip Resistor, 49.9 kohm, ± 1%, 63 mW, 0402 [1005 Metric], Thick Film, General Purpose"
			(at 255.27 82.55 0)
			(effects
				(font
					(size 1.27 1.27)
				)
				(hide yes)
			)
		)
		(property "MPN" "CR0402-FX-4992GLF"
			(at 275.59 62.23 0)
			(effects
				(font
					(size 1.27 1.27)
					(thickness 0.15)
				)
				(justify left bottom)
				(hide yes)
			)
		)
		(property "Manufacturer" "Bourns"
			(at 278.13 62.23 0)
			(effects
				(font
					(size 1.27 1.27)
					(thickness 0.15)
				)
				(justify left bottom)
				(hide yes)
			)
		)
		(property "License" "Apache-2.0"
			(at 280.67 62.23 0)
			(effects
				(font
					(size 1.27 1.27)
					(thickness 0.15)
				)
				(justify left bottom)
				(hide yes)
			)
		)
		(property "Author" "Antmicro"
			(at 283.21 62.23 0)
			(effects
				(font
					(size 1.27 1.27)
					(thickness 0.15)
				)
				(justify left bottom)
				(hide yes)
			)
		)
		(property "Val" "49k9"
			(at 254 82.55 0)
			(effects
				(font
					(size 1.27 1.27)
					(thickness 0.15)
				)
				(justify right)
			)
		)
		(property "Tolerance" "1%"
			(at 265.43 62.23 0)
			(effects
				(font
					(size 1.27 1.27)
				)
				(justify left bottom)
				(hide yes)
			)
		)
		(property "Public" ""
			(at 285.75 62.23 0)
			(effects
				(font
					(size 1.27 1.27)
				)
				(justify left bottom)
				(hide yes)
			)
		)
		(pin "1"
		)
		(pin "2"
		)
		(instances
			(project "polarfire-som"
				(path ""
					(reference "R38")
					(unit 1)
				)
			)
		)
	)
	(symbol
		(lib_id "antmicropower:+3V3")
		(at 189.23 87.63 0)
		(unit 1)
		(exclude_from_sim no)
		(in_bom yes)
		(on_board yes)
		(dnp no)
		(fields_autoplaced yes)
		(property "Reference" "#PWR0358"
			(at 204.47 90.17 0)
			(effects
				(font
					(size 1.27 1.27)
					(thickness 0.15)
				)
				(justify left bottom)
				(hide yes)
			)
		)
		(property "Value" "+3V3"
			(at 189.23 82.55 0)
			(effects
				(font
					(size 1.27 1.27)
					(thickness 0.15)
				)
			)
		)
		(property "Footprint" ""
			(at 204.47 95.25 0)
			(effects
				(font
					(size 1.27 1.27)
					(thickness 0.15)
				)
				(justify left bottom)
				(hide yes)
			)
		)
		(property "Datasheet" ""
			(at 204.47 97.79 0)
			(effects
				(font
					(size 1.27 1.27)
					(thickness 0.15)
				)
				(justify left bottom)
				(hide yes)
			)
		)
		(property "Description" ""
			(at 189.23 87.63 0)
			(effects
				(font
					(size 1.27 1.27)
				)
				(hide yes)
			)
		)
		(property "Author" "Antmicro"
			(at 204.47 95.25 0)
			(effects
				(font
					(size 1.27 1.27)
					(thickness 0.15)
				)
				(justify left bottom)
				(hide yes)
			)
		)
		(property "License" "Apache-2.0"
			(at 204.47 97.79 0)
			(effects
				(font
					(size 1.27 1.27)
					(thickness 0.15)
				)
				(justify left bottom)
				(hide yes)
			)
		)
		(pin "1"
		)
		(instances
			(project "polarfire-som"
				(path ""
					(reference "#PWR0358")
					(unit 1)
				)
			)
		)
	)
	(symbol
		(lib_id "antmicroResistors0402:R_49k9_0402")
		(at 242.57 82.55 90)
		(unit 1)
		(exclude_from_sim no)
		(in_bom yes)
		(on_board yes)
		(dnp no)
		(property "Reference" "R33"
			(at 241.3 73.66 0)
			(effects
				(font
					(size 1.27 1.27)
					(thickness 0.15)
				)
				(justify right)
			)
		)
		(property "Value" "R_49k9_0402"
			(at 255.27 62.23 0)
			(effects
				(font
					(size 1.27 1.27)
					(thickness 0.15)
				)
				(justify left bottom)
				(hide yes)
			)
		)
		(property "Footprint" "antmicro-footprints:R_0402_1005Metric"
			(at 257.81 62.23 0)
			(effects
				(font
					(size 1.27 1.27)
					(thickness 0.15)
				)
				(justify left bottom)
				(hide yes)
			)
		)
		(property "Datasheet" "https://www.bourns.com/docs/product-datasheets/cr.pdf"
			(at 260.35 62.23 0)
			(effects
				(font
					(size 1.27 1.27)
					(thickness 0.15)
				)
				(justify left bottom)
				(hide yes)
			)
		)
		(property "Description" "SMD Chip Resistor, 49.9 kohm, ± 1%, 63 mW, 0402 [1005 Metric], Thick Film, General Purpose"
			(at 242.57 82.55 0)
			(effects
				(font
					(size 1.27 1.27)
				)
				(hide yes)
			)
		)
		(property "MPN" "CR0402-FX-4992GLF"
			(at 262.89 62.23 0)
			(effects
				(font
					(size 1.27 1.27)
					(thickness 0.15)
				)
				(justify left bottom)
				(hide yes)
			)
		)
		(property "Manufacturer" "Bourns"
			(at 265.43 62.23 0)
			(effects
				(font
					(size 1.27 1.27)
					(thickness 0.15)
				)
				(justify left bottom)
				(hide yes)
			)
		)
		(property "License" "Apache-2.0"
			(at 267.97 62.23 0)
			(effects
				(font
					(size 1.27 1.27)
					(thickness 0.15)
				)
				(justify left bottom)
				(hide yes)
			)
		)
		(property "Author" "Antmicro"
			(at 270.51 62.23 0)
			(effects
				(font
					(size 1.27 1.27)
					(thickness 0.15)
				)
				(justify left bottom)
				(hide yes)
			)
		)
		(property "Val" "49k9"
			(at 241.3 82.55 0)
			(effects
				(font
					(size 1.27 1.27)
					(thickness 0.15)
				)
				(justify right)
			)
		)
		(property "Tolerance" "1%"
			(at 252.73 62.23 0)
			(effects
				(font
					(size 1.27 1.27)
				)
				(justify left bottom)
				(hide yes)
			)
		)
		(property "Public" ""
			(at 273.05 62.23 0)
			(effects
				(font
					(size 1.27 1.27)
				)
				(justify left bottom)
				(hide yes)
			)
		)
		(pin "1"
		)
		(pin "2"
		)
		(instances
			(project "polarfire-som"
				(path ""
					(reference "R33")
					(unit 1)
				)
			)
		)
	)
	(symbol
		(lib_id "antmicroPMICPowerDistributionSwitchesLoadDrivers:TPS2117DRLR")
		(at 66.04 232.41 0)
		(unit 1)
		(exclude_from_sim no)
		(in_bom yes)
		(on_board yes)
		(dnp no)
		(property "Reference" "U10"
			(at 74.93 225.425 0)
			(effects
				(font
					(size 1.27 1.27)
					(thickness 0.15)
				)
			)
		)
		(property "Value" "TPS2117DRLR"
			(at 74.93 227.965 0)
			(effects
				(font
					(size 1.27 1.27)
					(thickness 0.15)
				)
			)
		)
		(property "Footprint" "antmicro-footprints:SOT-583"
			(at 100.33 237.49 0)
			(effects
				(font
					(size 1.27 1.27)
					(thickness 0.15)
				)
				(justify left bottom)
				(hide yes)
			)
		)
		(property "Datasheet" "https://www.ti.com/lit/ds/symlink/tps2117.pdf"
			(at 100.33 240.03 0)
			(effects
				(font
					(size 1.27 1.27)
					(thickness 0.15)
				)
				(justify left bottom)
				(hide yes)
			)
		)
		(property "Description" "TPS2117 1.6-V to 5.5-V, 4-A Low IQ Power Mux With Manual and Priority Switchover"
			(at 66.04 232.41 0)
			(effects
				(font
					(size 1.27 1.27)
				)
				(hide yes)
			)
		)
		(property "Manufacturer" "Texas Instruments"
			(at 100.33 242.57 0)
			(effects
				(font
					(size 1.27 1.27)
					(thickness 0.15)
				)
				(justify left bottom)
				(hide yes)
			)
		)
		(property "MPN" "TPS2117DRLR"
			(at 100.33 245.11 0)
			(effects
				(font
					(size 1.27 1.27)
					(thickness 0.15)
				)
				(justify left bottom)
				(hide yes)
			)
		)
		(property "Author" "Antmicro"
			(at 100.33 247.65 0)
			(effects
				(font
					(size 1.27 1.27)
					(thickness 0.15)
				)
				(justify left bottom)
				(hide yes)
			)
		)
		(property "License" "Apache-2.0"
			(at 100.33 250.19 0)
			(effects
				(font
					(size 1.27 1.27)
					(thickness 0.15)
				)
				(justify left bottom)
				(hide yes)
			)
		)
		(pin "1"
		)
		(pin "2"
		)
		(pin "3"
		)
		(pin "4"
		)
		(pin "5"
		)
		(pin "6"
		)
		(pin "7"
		)
		(pin "8"
		)
		(instances
			(project "polarfire-som"
				(path ""
					(reference "U10")
					(unit 1)
				)
			)
		)
	)
	(symbol
		(lib_id "antmicroMemory:SDINBDG4-8G")
		(at 205.74 88.9 0)
		(unit 1)
		(exclude_from_sim no)
		(in_bom yes)
		(on_board yes)
		(dnp no)
		(fields_autoplaced yes)
		(property "Reference" "U2"
			(at 217.805 81.28 0)
			(effects
				(font
					(size 1.27 1.27)
					(thickness 0.15)
				)
			)
		)
		(property "Value" "SDINBDG4-8G"
			(at 243.84 96.52 0)
			(effects
				(font
					(size 1.27 1.27)
					(thickness 0.15)
				)
				(justify left bottom)
				(hide yes)
			)
		)
		(property "Footprint" "antmicro-footprints:BGA-196-153_11.5x13mm_Layout14x14_P0.5x0.5mm"
			(at 243.84 99.06 0)
			(effects
				(font
					(size 1.27 1.27)
					(thickness 0.15)
				)
				(justify left bottom)
				(hide yes)
			)
		)
		(property "Datasheet" "https://www.infineon.com/dgdl/Infineon-AN98491_Recommended_PCB_Routing_Guidelines_for_a_Infineon_e.MMC_Memory_Device-ApplicationNotes-v05_00-EN.pdf?fileId=8ac78c8c7d718a49017d71baea97084d"
			(at 243.84 101.6 0)
			(effects
				(font
					(size 1.27 1.27)
					(thickness 0.15)
				)
				(justify left bottom)
				(hide yes)
			)
		)
		(property "Description" "NAND Flash Serial e-MMC 64G-bit SanDisk iNAND 7250 Industrial emmc"
			(at 205.74 88.9 0)
			(effects
				(font
					(size 1.27 1.27)
				)
				(hide yes)
			)
		)
		(property "MPN" "SDINBDG4-8G"
			(at 217.805 83.82 0)
			(effects
				(font
					(size 1.27 1.27)
					(thickness 0.15)
				)
			)
		)
		(property "Manufacturer" "SanDisk"
			(at 243.84 104.14 0)
			(effects
				(font
					(size 1.27 1.27)
					(thickness 0.15)
				)
				(justify left bottom)
				(hide yes)
			)
		)
		(property "VSD_class" "eMMC"
			(at 243.84 106.68 0)
			(effects
				(font
					(size 1.27 1.27)
					(thickness 0.15)
				)
				(justify left bottom)
				(hide yes)
			)
		)
		(property "Author" "Antmicro"
			(at 243.84 109.22 0)
			(effects
				(font
					(size 1.27 1.27)
					(thickness 0.15)
				)
				(justify left bottom)
				(hide yes)
			)
		)
		(property "License" "Apache-2.0"
			(at 243.84 111.76 0)
			(effects
				(font
					(size 1.27 1.27)
					(thickness 0.15)
				)
				(justify left bottom)
				(hide yes)
			)
		)
		(pin "A3"
		)
		(pin "A4"
		)
		(pin "A5"
		)
		(pin "A6"
		)
		(pin "B2"
		)
		(pin "B3"
		)
		(pin "B4"
		)
		(pin "B5"
		)
		(pin "B6"
		)
		(pin "C2"
		)
		(pin "C4"
		)
		(pin "C6"
		)
		(pin "E10"
		)
		(pin "E5"
		)
		(pin "E6"
		)
		(pin "E7"
		)
		(pin "E9"
		)
		(pin "F10"
		)
		(pin "F5"
		)
		(pin "G5"
		)
		(pin "H10"
		)
		(pin "H5"
		)
		(pin "J10"
		)
		(pin "J5"
		)
		(pin "K10"
		)
		(pin "K5"
		)
		(pin "K8"
		)
		(pin "K9"
		)
		(pin "M4"
		)
		(pin "M5"
		)
		(pin "M6"
		)
		(pin "N2"
		)
		(pin "N4"
		)
		(pin "N5"
		)
		(pin "P3"
		)
		(pin "P4"
		)
		(pin "P5"
		)
		(pin "P6"
		)
		(pin "B11"
		)
		(pin "B12"
		)
		(pin "B13"
		)
		(pin "P7"
		)
		(pin "A7"
		)
		(pin "G10"
		)
		(pin "G3"
		)
		(pin "H13"
		)
		(pin "H14"
		)
		(pin "H2"
		)
		(pin "M12"
		)
		(pin "M13"
		)
		(pin "M14"
		)
		(pin "H3"
		)
		(pin "J12"
		)
		(pin "J13"
		)
		(pin "L1"
		)
		(pin "L12"
		)
		(pin "L13"
		)
		(pin "E3"
		)
		(pin "F1"
		)
		(pin "F12"
		)
		(pin "P14"
		)
		(pin "A1"
		)
		(pin "A10"
		)
		(pin "D14"
		)
		(pin "D2"
		)
		(pin "D3"
		)
		(pin "G2"
		)
		(pin "H1"
		)
		(pin "H12"
		)
		(pin "N10"
		)
		(pin "N11"
		)
		(pin "N12"
		)
		(pin "N13"
		)
		(pin "N14"
		)
		(pin "N3"
		)
		(pin "N9"
		)
		(pin "P1"
		)
		(pin "P11"
		)
		(pin "C11"
		)
		(pin "C12"
		)
		(pin "C13"
		)
		(pin "E8"
		)
		(pin "M8"
		)
		(pin "P8"
		)
		(pin "P9"
		)
		(pin "M2"
		)
		(pin "M3"
		)
		(pin "M7"
		)
		(pin "M1"
		)
		(pin "M10"
		)
		(pin "M11"
		)
		(pin "B14"
		)
		(pin "B7"
		)
		(pin "B8"
		)
		(pin "A13"
		)
		(pin "A2"
		)
		(pin "A8"
		)
		(pin "P12"
		)
		(pin "P13"
		)
		(pin "P2"
		)
		(pin "D1"
		)
		(pin "D12"
		)
		(pin "D13"
		)
		(pin "B1"
		)
		(pin "B10"
		)
		(pin "L14"
		)
		(pin "L2"
		)
		(pin "L3"
		)
		(pin "F3"
		)
		(pin "G1"
		)
		(pin "G12"
		)
		(pin "J3"
		)
		(pin "K12"
		)
		(pin "K13"
		)
		(pin "K14"
		)
		(pin "K2"
		)
		(pin "K3"
		)
		(pin "E13"
		)
		(pin "E14"
		)
		(pin "E2"
		)
		(pin "A11"
		)
		(pin "A12"
		)
		(pin "A14"
		)
		(pin "N6"
		)
		(pin "N7"
		)
		(pin "N8"
		)
		(pin "K6"
		)
		(pin "K7"
		)
		(pin "P10"
		)
		(pin "J14"
		)
		(pin "J2"
		)
		(pin "K1"
		)
		(pin "F14"
		)
		(pin "M9"
		)
		(pin "N1"
		)
		(pin "D4"
		)
		(pin "E1"
		)
		(pin "E12"
		)
		(pin "G13"
		)
		(pin "G14"
		)
		(pin "J1"
		)
		(pin "C14"
		)
		(pin "C3"
		)
		(pin "C5"
		)
		(pin "B9"
		)
		(pin "C1"
		)
		(pin "C10"
		)
		(pin "A9"
		)
		(pin "F13"
		)
		(pin "F2"
		)
		(pin "C7"
		)
		(pin "C8"
		)
		(pin "C9"
		)
		(instances
			(project "polarfire-som"
				(path ""
					(reference "U2")
					(unit 1)
				)
			)
		)
	)
	(symbol
		(lib_id "antmicropower:+3V3")
		(at 35.56 238.76 0)
		(unit 1)
		(exclude_from_sim no)
		(in_bom yes)
		(on_board yes)
		(dnp no)
		(property "Reference" "#PWR0202"
			(at 50.8 241.3 0)
			(effects
				(font
					(size 1.27 1.27)
					(thickness 0.15)
				)
				(justify left bottom)
				(hide yes)
			)
		)
		(property "Value" "+3V3"
			(at 35.56 234.95 0)
			(effects
				(font
					(size 1.27 1.27)
					(thickness 0.15)
				)
			)
		)
		(property "Footprint" ""
			(at 50.8 246.38 0)
			(effects
				(font
					(size 1.27 1.27)
					(thickness 0.15)
				)
				(justify left bottom)
				(hide yes)
			)
		)
		(property "Datasheet" ""
			(at 50.8 248.92 0)
			(effects
				(font
					(size 1.27 1.27)
					(thickness 0.15)
				)
				(justify left bottom)
				(hide yes)
			)
		)
		(property "Description" ""
			(at 35.56 238.76 0)
			(effects
				(font
					(size 1.27 1.27)
				)
				(hide yes)
			)
		)
		(property "Author" "Antmicro"
			(at 50.8 246.38 0)
			(effects
				(font
					(size 1.27 1.27)
					(thickness 0.15)
				)
				(justify left bottom)
				(hide yes)
			)
		)
		(property "License" "Apache-2.0"
			(at 50.8 248.92 0)
			(effects
				(font
					(size 1.27 1.27)
					(thickness 0.15)
				)
				(justify left bottom)
				(hide yes)
			)
		)
		(pin "1"
		)
		(instances
			(project "polarfire-som"
				(path ""
					(reference "#PWR0202")
					(unit 1)
				)
			)
		)
	)
	(symbol
		(lib_id "antmicropower:GND")
		(at 86.36 209.55 0)
		(unit 1)
		(exclude_from_sim no)
		(in_bom yes)
		(on_board yes)
		(dnp no)
		(property "Reference" "#PWR0192"
			(at 95.25 212.09 0)
			(effects
				(font
					(size 1.27 1.27)
					(thickness 0.15)
				)
				(justify left bottom)
				(hide yes)
			)
		)
		(property "Value" "GND"
			(at 86.36 213.36 0)
			(effects
				(font
					(size 1.27 1.27)
					(thickness 0.15)
				)
			)
		)
		(property "Footprint" ""
			(at 95.25 217.17 0)
			(effects
				(font
					(size 1.27 1.27)
					(thickness 0.15)
				)
				(justify left bottom)
				(hide yes)
			)
		)
		(property "Datasheet" ""
			(at 95.25 222.25 0)
			(effects
				(font
					(size 1.27 1.27)
					(thickness 0.15)
				)
				(justify left bottom)
				(hide yes)
			)
		)
		(property "Description" ""
			(at 86.36 209.55 0)
			(effects
				(font
					(size 1.27 1.27)
				)
				(hide yes)
			)
		)
		(property "Author" "Antmicro"
			(at 95.25 217.17 0)
			(effects
				(font
					(size 1.27 1.27)
					(thickness 0.15)
				)
				(justify left bottom)
				(hide yes)
			)
		)
		(property "License" "Apache-2.0"
			(at 95.25 219.71 0)
			(effects
				(font
					(size 1.27 1.27)
					(thickness 0.15)
				)
				(justify left bottom)
				(hide yes)
			)
		)
		(pin "1"
		)
		(instances
			(project "polarfire-som"
				(path ""
					(reference "#PWR0192")
					(unit 1)
				)
			)
		)
	)
	(symbol
		(lib_id "antmicroCapacitors0402:C_100n_0402")
		(at 151.13 72.39 90)
		(unit 1)
		(exclude_from_sim no)
		(in_bom yes)
		(on_board yes)
		(dnp no)
		(property "Reference" "C71"
			(at 151.13 67.31 90)
			(effects
				(font
					(size 1.27 1.27)
					(thickness 0.15)
				)
				(justify right)
			)
		)
		(property "Value" "C_100n_0402"
			(at 161.29 52.07 0)
			(effects
				(font
					(size 1.27 1.27)
					(thickness 0.15)
				)
				(justify left bottom)
				(hide yes)
			)
		)
		(property "Footprint" "antmicro-footprints:C_0402_1005Metric"
			(at 163.83 52.07 0)
			(effects
				(font
					(size 1.27 1.27)
					(thickness 0.15)
				)
				(justify left bottom)
				(hide yes)
			)
		)
		(property "Datasheet" "https://www.murata.com/products/productdetail?partno=GRM155R61H104KE14%23"
			(at 166.37 52.07 0)
			(effects
				(font
					(size 1.27 1.27)
					(thickness 0.15)
				)
				(justify left bottom)
				(hide yes)
			)
		)
		(property "Description" "SMD Multilayer Ceramic Capacitor, 0.1 µF, 50 V, 0402 [1005 Metric], ± 10%, X5R, GRM Series"
			(at 151.13 72.39 0)
			(effects
				(font
					(size 1.27 1.27)
				)
				(hide yes)
			)
		)
		(property "MPN" "GRM155R61H104KE14D"
			(at 168.91 52.07 0)
			(effects
				(font
					(size 1.27 1.27)
					(thickness 0.15)
				)
				(justify left bottom)
				(hide yes)
			)
		)
		(property "Manufacturer" "Murata"
			(at 171.45 52.07 0)
			(effects
				(font
					(size 1.27 1.27)
					(thickness 0.15)
				)
				(justify left bottom)
				(hide yes)
			)
		)
		(property "License" "Apache-2.0"
			(at 173.99 52.07 0)
			(effects
				(font
					(size 1.27 1.27)
					(thickness 0.15)
				)
				(justify left bottom)
				(hide yes)
			)
		)
		(property "Author" "Antmicro"
			(at 176.53 52.07 0)
			(effects
				(font
					(size 1.27 1.27)
					(thickness 0.15)
				)
				(justify left bottom)
				(hide yes)
			)
		)
		(property "Val" "100n"
			(at 151.13 72.39 90)
			(effects
				(font
					(size 1.27 1.27)
					(thickness 0.15)
				)
				(justify right)
			)
		)
		(property "Voltage" "50V"
			(at 179.07 52.07 0)
			(effects
				(font
					(size 1.27 1.27)
				)
				(justify left bottom)
				(hide yes)
			)
		)
		(property "Dielectric" "X5R"
			(at 181.61 52.07 0)
			(effects
				(font
					(size 1.27 1.27)
				)
				(justify left bottom)
				(hide yes)
			)
		)
		(property "Public" ""
			(at 184.15 52.07 0)
			(effects
				(font
					(size 1.27 1.27)
				)
				(justify left bottom)
				(hide yes)
			)
		)
		(pin "1"
		)
		(pin "2"
		)
		(instances
			(project "polarfire-som"
				(path ""
					(reference "C71")
					(unit 1)
				)
			)
		)
	)
	(symbol
		(lib_id "antmicroResistors0402:R_49k9_0402")
		(at 247.65 82.55 90)
		(unit 1)
		(exclude_from_sim no)
		(in_bom yes)
		(on_board yes)
		(dnp no)
		(property "Reference" "R35"
			(at 246.38 73.66 0)
			(effects
				(font
					(size 1.27 1.27)
					(thickness 0.15)
				)
				(justify right)
			)
		)
		(property "Value" "R_49k9_0402"
			(at 260.35 62.23 0)
			(effects
				(font
					(size 1.27 1.27)
					(thickness 0.15)
				)
				(justify left bottom)
				(hide yes)
			)
		)
		(property "Footprint" "antmicro-footprints:R_0402_1005Metric"
			(at 262.89 62.23 0)
			(effects
				(font
					(size 1.27 1.27)
					(thickness 0.15)
				)
				(justify left bottom)
				(hide yes)
			)
		)
		(property "Datasheet" "https://www.bourns.com/docs/product-datasheets/cr.pdf"
			(at 265.43 62.23 0)
			(effects
				(font
					(size 1.27 1.27)
					(thickness 0.15)
				)
				(justify left bottom)
				(hide yes)
			)
		)
		(property "Description" "SMD Chip Resistor, 49.9 kohm, ± 1%, 63 mW, 0402 [1005 Metric], Thick Film, General Purpose"
			(at 247.65 82.55 0)
			(effects
				(font
					(size 1.27 1.27)
				)
				(hide yes)
			)
		)
		(property "MPN" "CR0402-FX-4992GLF"
			(at 267.97 62.23 0)
			(effects
				(font
					(size 1.27 1.27)
					(thickness 0.15)
				)
				(justify left bottom)
				(hide yes)
			)
		)
		(property "Manufacturer" "Bourns"
			(at 270.51 62.23 0)
			(effects
				(font
					(size 1.27 1.27)
					(thickness 0.15)
				)
				(justify left bottom)
				(hide yes)
			)
		)
		(property "License" "Apache-2.0"
			(at 273.05 62.23 0)
			(effects
				(font
					(size 1.27 1.27)
					(thickness 0.15)
				)
				(justify left bottom)
				(hide yes)
			)
		)
		(property "Author" "Antmicro"
			(at 275.59 62.23 0)
			(effects
				(font
					(size 1.27 1.27)
					(thickness 0.15)
				)
				(justify left bottom)
				(hide yes)
			)
		)
		(property "Val" "49k9"
			(at 246.38 82.55 0)
			(effects
				(font
					(size 1.27 1.27)
					(thickness 0.15)
				)
				(justify right)
			)
		)
		(property "Tolerance" "1%"
			(at 257.81 62.23 0)
			(effects
				(font
					(size 1.27 1.27)
				)
				(justify left bottom)
				(hide yes)
			)
		)
		(property "Public" ""
			(at 278.13 62.23 0)
			(effects
				(font
					(size 1.27 1.27)
				)
				(justify left bottom)
				(hide yes)
			)
		)
		(pin "1"
		)
		(pin "2"
		)
		(instances
			(project "polarfire-som"
				(path ""
					(reference "R35")
					(unit 1)
				)
			)
		)
	)
	(symbol
		(lib_id "antmicroCapacitors0402:C_100n_0402")
		(at 165.1 127 90)
		(unit 1)
		(exclude_from_sim no)
		(in_bom yes)
		(on_board yes)
		(dnp no)
		(property "Reference" "C77"
			(at 165.1 121.92 90)
			(effects
				(font
					(size 1.27 1.27)
					(thickness 0.15)
				)
				(justify right)
			)
		)
		(property "Value" "C_100n_0402"
			(at 175.26 106.68 0)
			(effects
				(font
					(size 1.27 1.27)
					(thickness 0.15)
				)
				(justify left bottom)
				(hide yes)
			)
		)
		(property "Footprint" "antmicro-footprints:C_0402_1005Metric"
			(at 177.8 106.68 0)
			(effects
				(font
					(size 1.27 1.27)
					(thickness 0.15)
				)
				(justify left bottom)
				(hide yes)
			)
		)
		(property "Datasheet" "https://www.murata.com/products/productdetail?partno=GRM155R61H104KE14%23"
			(at 180.34 106.68 0)
			(effects
				(font
					(size 1.27 1.27)
					(thickness 0.15)
				)
				(justify left bottom)
				(hide yes)
			)
		)
		(property "Description" "SMD Multilayer Ceramic Capacitor, 0.1 µF, 50 V, 0402 [1005 Metric], ± 10%, X5R, GRM Series"
			(at 165.1 127 0)
			(effects
				(font
					(size 1.27 1.27)
				)
				(hide yes)
			)
		)
		(property "MPN" "GRM155R61H104KE14D"
			(at 182.88 106.68 0)
			(effects
				(font
					(size 1.27 1.27)
					(thickness 0.15)
				)
				(justify left bottom)
				(hide yes)
			)
		)
		(property "Manufacturer" "Murata"
			(at 185.42 106.68 0)
			(effects
				(font
					(size 1.27 1.27)
					(thickness 0.15)
				)
				(justify left bottom)
				(hide yes)
			)
		)
		(property "License" "Apache-2.0"
			(at 187.96 106.68 0)
			(effects
				(font
					(size 1.27 1.27)
					(thickness 0.15)
				)
				(justify left bottom)
				(hide yes)
			)
		)
		(property "Author" "Antmicro"
			(at 190.5 106.68 0)
			(effects
				(font
					(size 1.27 1.27)
					(thickness 0.15)
				)
				(justify left bottom)
				(hide yes)
			)
		)
		(property "Val" "100n"
			(at 165.1 127 90)
			(effects
				(font
					(size 1.27 1.27)
					(thickness 0.15)
				)
				(justify right)
			)
		)
		(property "Voltage" "50V"
			(at 193.04 106.68 0)
			(effects
				(font
					(size 1.27 1.27)
				)
				(justify left bottom)
				(hide yes)
			)
		)
		(property "Dielectric" "X5R"
			(at 195.58 106.68 0)
			(effects
				(font
					(size 1.27 1.27)
				)
				(justify left bottom)
				(hide yes)
			)
		)
		(property "Public" ""
			(at 198.12 106.68 0)
			(effects
				(font
					(size 1.27 1.27)
				)
				(justify left bottom)
				(hide yes)
			)
		)
		(pin "1"
		)
		(pin "2"
		)
		(instances
			(project "polarfire-som"
				(path ""
					(reference "C77")
					(unit 1)
				)
			)
		)
	)
	(symbol
		(lib_id "antmicroPMICPowerDistributionSwitchesLoadDrivers:TPS2117DRLR")
		(at 66.04 200.66 0)
		(unit 1)
		(exclude_from_sim no)
		(in_bom yes)
		(on_board yes)
		(dnp no)
		(property "Reference" "U9"
			(at 74.93 193.04 0)
			(effects
				(font
					(size 1.27 1.27)
					(thickness 0.15)
				)
			)
		)
		(property "Value" "TPS2117DRLR"
			(at 74.93 195.58 0)
			(effects
				(font
					(size 1.27 1.27)
					(thickness 0.15)
				)
			)
		)
		(property "Footprint" "antmicro-footprints:SOT-583"
			(at 100.33 205.74 0)
			(effects
				(font
					(size 1.27 1.27)
					(thickness 0.15)
				)
				(justify left bottom)
				(hide yes)
			)
		)
		(property "Datasheet" "https://www.ti.com/lit/ds/symlink/tps2117.pdf"
			(at 100.33 208.28 0)
			(effects
				(font
					(size 1.27 1.27)
					(thickness 0.15)
				)
				(justify left bottom)
				(hide yes)
			)
		)
		(property "Description" "TPS2117 1.6-V to 5.5-V, 4-A Low IQ Power Mux With Manual and Priority Switchover"
			(at 66.04 200.66 0)
			(effects
				(font
					(size 1.27 1.27)
				)
				(hide yes)
			)
		)
		(property "Manufacturer" "Texas Instruments"
			(at 100.33 210.82 0)
			(effects
				(font
					(size 1.27 1.27)
					(thickness 0.15)
				)
				(justify left bottom)
				(hide yes)
			)
		)
		(property "MPN" "TPS2117DRLR"
			(at 100.33 213.36 0)
			(effects
				(font
					(size 1.27 1.27)
					(thickness 0.15)
				)
				(justify left bottom)
				(hide yes)
			)
		)
		(property "Author" "Antmicro"
			(at 100.33 215.9 0)
			(effects
				(font
					(size 1.27 1.27)
					(thickness 0.15)
				)
				(justify left bottom)
				(hide yes)
			)
		)
		(property "License" "Apache-2.0"
			(at 100.33 218.44 0)
			(effects
				(font
					(size 1.27 1.27)
					(thickness 0.15)
				)
				(justify left bottom)
				(hide yes)
			)
		)
		(pin "1"
		)
		(pin "2"
		)
		(pin "3"
		)
		(pin "4"
		)
		(pin "5"
		)
		(pin "6"
		)
		(pin "7"
		)
		(pin "8"
		)
		(instances
			(project "polarfire-som"
				(path ""
					(reference "U9")
					(unit 1)
				)
			)
		)
	)
	(symbol
		(lib_id "antmicroCapacitors0402:C_10u_0402")
		(at 146.05 127 90)
		(unit 1)
		(exclude_from_sim no)
		(in_bom yes)
		(on_board yes)
		(dnp no)
		(property "Reference" "C80"
			(at 146.05 121.92 90)
			(effects
				(font
					(size 1.27 1.27)
					(thickness 0.15)
				)
				(justify right)
			)
		)
		(property "Value" "C_10u_0402"
			(at 156.21 106.68 0)
			(effects
				(font
					(size 1.27 1.27)
					(thickness 0.15)
				)
				(justify left bottom)
				(hide yes)
			)
		)
		(property "Footprint" "antmicro-footprints:C_0402_1005Metric"
			(at 158.75 106.68 0)
			(effects
				(font
					(size 1.27 1.27)
					(thickness 0.15)
				)
				(justify left bottom)
				(hide yes)
			)
		)
		(property "Datasheet" "https://www.yageo.com/en/Chart/Download/pdf/CC0402MRX5R5BB106"
			(at 161.29 106.68 0)
			(effects
				(font
					(size 1.27 1.27)
					(thickness 0.15)
				)
				(justify left bottom)
				(hide yes)
			)
		)
		(property "Description" "SMD Multilayer Ceramic Capacitor, 10 µF, 6.3 V, 0402 [1005 Metric], ± 20%, X5R, CC Series"
			(at 146.05 127 0)
			(effects
				(font
					(size 1.27 1.27)
				)
				(hide yes)
			)
		)
		(property "MPN" "CC0402MRX5R5BB106"
			(at 163.83 106.68 0)
			(effects
				(font
					(size 1.27 1.27)
					(thickness 0.15)
				)
				(justify left bottom)
				(hide yes)
			)
		)
		(property "Manufacturer" "YAGEO"
			(at 166.37 106.68 0)
			(effects
				(font
					(size 1.27 1.27)
					(thickness 0.15)
				)
				(justify left bottom)
				(hide yes)
			)
		)
		(property "License" "Apache-2.0"
			(at 168.91 106.68 0)
			(effects
				(font
					(size 1.27 1.27)
					(thickness 0.15)
				)
				(justify left bottom)
				(hide yes)
			)
		)
		(property "Author" "Antmicro"
			(at 171.45 106.68 0)
			(effects
				(font
					(size 1.27 1.27)
					(thickness 0.15)
				)
				(justify left bottom)
				(hide yes)
			)
		)
		(property "Val" "10u"
			(at 146.05 127 90)
			(effects
				(font
					(size 1.27 1.27)
					(thickness 0.15)
				)
				(justify right)
			)
		)
		(property "Voltage" ""
			(at 173.99 106.68 0)
			(effects
				(font
					(size 1.27 1.27)
				)
				(justify left bottom)
				(hide yes)
			)
		)
		(property "Dielectric" ""
			(at 176.53 106.68 0)
			(effects
				(font
					(size 1.27 1.27)
				)
				(justify left bottom)
				(hide yes)
			)
		)
		(property "Public" ""
			(at 179.07 106.68 0)
			(effects
				(font
					(size 1.27 1.27)
				)
				(justify left bottom)
				(hide yes)
			)
		)
		(pin "1"
		)
		(pin "2"
		)
		(instances
			(project "polarfire-som"
				(path ""
					(reference "C80")
					(unit 1)
				)
			)
		)
	)
	(symbol
		(lib_id "antmicropower:GND")
		(at 128.27 220.98 0)
		(unit 1)
		(exclude_from_sim no)
		(in_bom yes)
		(on_board yes)
		(dnp no)
		(property "Reference" "#PWR0194"
			(at 137.16 223.52 0)
			(effects
				(font
					(size 1.27 1.27)
					(thickness 0.15)
				)
				(justify left bottom)
				(hide yes)
			)
		)
		(property "Value" "GND"
			(at 128.27 224.79 0)
			(effects
				(font
					(size 1.27 1.27)
					(thickness 0.15)
				)
			)
		)
		(property "Footprint" ""
			(at 137.16 228.6 0)
			(effects
				(font
					(size 1.27 1.27)
					(thickness 0.15)
				)
				(justify left bottom)
				(hide yes)
			)
		)
		(property "Datasheet" ""
			(at 137.16 233.68 0)
			(effects
				(font
					(size 1.27 1.27)
					(thickness 0.15)
				)
				(justify left bottom)
				(hide yes)
			)
		)
		(property "Description" ""
			(at 128.27 220.98 0)
			(effects
				(font
					(size 1.27 1.27)
				)
				(hide yes)
			)
		)
		(property "Author" "Antmicro"
			(at 137.16 228.6 0)
			(effects
				(font
					(size 1.27 1.27)
					(thickness 0.15)
				)
				(justify left bottom)
				(hide yes)
			)
		)
		(property "License" "Apache-2.0"
			(at 137.16 231.14 0)
			(effects
				(font
					(size 1.27 1.27)
					(thickness 0.15)
				)
				(justify left bottom)
				(hide yes)
			)
		)
		(pin "1"
		)
		(instances
			(project "polarfire-som"
				(path ""
					(reference "#PWR0194")
					(unit 1)
				)
			)
		)
	)
	(symbol
		(lib_id "antmicroResistors0402:R_0R_0402")
		(at 90.17 232.41 0)
		(unit 1)
		(exclude_from_sim no)
		(in_bom yes)
		(on_board yes)
		(dnp no)
		(property "Reference" "R56"
			(at 95.25 227.33 0)
			(effects
				(font
					(size 1.27 1.27)
					(thickness 0.15)
				)
				(justify right)
			)
		)
		(property "Value" "R_0R_0402"
			(at 110.49 245.11 0)
			(effects
				(font
					(size 1.27 1.27)
					(thickness 0.15)
				)
				(justify left bottom)
				(hide yes)
			)
		)
		(property "Footprint" "antmicro-footprints:R_0402_1005Metric"
			(at 110.49 247.65 0)
			(effects
				(font
					(size 1.27 1.27)
					(thickness 0.15)
				)
				(justify left bottom)
				(hide yes)
			)
		)
		(property "Datasheet" "https://industrial.panasonic.com/cdbs/www-data/pdf/RDA0000/AOA0000C301.pdf"
			(at 110.49 250.19 0)
			(effects
				(font
					(size 1.27 1.27)
					(thickness 0.15)
				)
				(justify left bottom)
				(hide yes)
			)
		)
		(property "Description" "SMD Chip Resistor, Jumper, 0 ohm, 100 mW, 0402 [1005 Metric], Thick Film, General Purpose"
			(at 90.17 232.41 0)
			(effects
				(font
					(size 1.27 1.27)
				)
				(hide yes)
			)
		)
		(property "MPN" "ERJ2GE0R00X"
			(at 110.49 252.73 0)
			(effects
				(font
					(size 1.27 1.27)
					(thickness 0.15)
				)
				(justify left bottom)
				(hide yes)
			)
		)
		(property "Manufacturer" "Panasonic"
			(at 110.49 255.27 0)
			(effects
				(font
					(size 1.27 1.27)
					(thickness 0.15)
				)
				(justify left bottom)
				(hide yes)
			)
		)
		(property "License" "Apache-2.0"
			(at 110.49 257.81 0)
			(effects
				(font
					(size 1.27 1.27)
					(thickness 0.15)
				)
				(justify left bottom)
				(hide yes)
			)
		)
		(property "Author" "Antmicro"
			(at 110.49 260.35 0)
			(effects
				(font
					(size 1.27 1.27)
					(thickness 0.15)
				)
				(justify left bottom)
				(hide yes)
			)
		)
		(property "Val" "0R"
			(at 93.98 229.87 0)
			(effects
				(font
					(size 1.27 1.27)
					(thickness 0.15)
				)
				(justify right)
			)
		)
		(property "Tolerance" "~"
			(at 110.49 242.57 0)
			(effects
				(font
					(size 1.27 1.27)
				)
				(justify left bottom)
				(hide yes)
			)
		)
		(property "Current" "1A"
			(at 110.49 262.89 0)
			(effects
				(font
					(size 1.27 1.27)
					(thickness 0.15)
				)
				(justify left bottom)
				(hide yes)
			)
		)
		(property "Public" ""
			(at 110.49 262.89 0)
			(effects
				(font
					(size 1.27 1.27)
				)
				(justify left bottom)
				(hide yes)
			)
		)
		(pin "1"
		)
		(pin "2"
		)
		(instances
			(project "polarfire-som"
				(path ""
					(reference "R56")
					(unit 1)
				)
			)
		)
	)
	(symbol
		(lib_id "antmicropower:+1V8")
		(at 63.5 199.39 0)
		(unit 1)
		(exclude_from_sim no)
		(in_bom yes)
		(on_board yes)
		(dnp no)
		(fields_autoplaced yes)
		(property "Reference" "#PWR084"
			(at 78.74 201.93 0)
			(effects
				(font
					(size 1.27 1.27)
					(thickness 0.15)
				)
				(justify left bottom)
				(hide yes)
			)
		)
		(property "Value" "+1V8"
			(at 63.5 194.31 0)
			(effects
				(font
					(size 1.27 1.27)
					(thickness 0.15)
				)
			)
		)
		(property "Footprint" ""
			(at 78.74 207.01 0)
			(effects
				(font
					(size 1.27 1.27)
					(thickness 0.15)
				)
				(justify left bottom)
				(hide yes)
			)
		)
		(property "Datasheet" ""
			(at 78.74 209.55 0)
			(effects
				(font
					(size 1.27 1.27)
					(thickness 0.15)
				)
				(justify left bottom)
				(hide yes)
			)
		)
		(property "Description" ""
			(at 63.5 199.39 0)
			(effects
				(font
					(size 1.27 1.27)
				)
				(hide yes)
			)
		)
		(property "Author" "Antmicro"
			(at 78.74 207.01 0)
			(effects
				(font
					(size 1.27 1.27)
					(thickness 0.15)
				)
				(justify left bottom)
				(hide yes)
			)
		)
		(property "License" "Apache-2.0"
			(at 78.74 209.55 0)
			(effects
				(font
					(size 1.27 1.27)
					(thickness 0.15)
				)
				(justify left bottom)
				(hide yes)
			)
		)
		(pin "1"
		)
		(instances
			(project "polarfire-som"
				(path ""
					(reference "#PWR084")
					(unit 1)
				)
			)
		)
	)
	(symbol
		(lib_id "antmicropower:+2V5")
		(at 63.5 231.14 0)
		(unit 1)
		(exclude_from_sim no)
		(in_bom yes)
		(on_board yes)
		(dnp no)
		(fields_autoplaced yes)
		(property "Reference" "#PWR0201"
			(at 63.5 234.95 0)
			(effects
				(font
					(size 1.27 1.27)
				)
				(hide yes)
			)
		)
		(property "Value" "+2V5"
			(at 63.5 226.06 0)
			(effects
				(font
					(size 1.27 1.27)
				)
			)
		)
		(property "Footprint" ""
			(at 63.5 231.14 0)
			(effects
				(font
					(size 1.27 1.27)
				)
				(hide yes)
			)
		)
		(property "Datasheet" ""
			(at 63.5 231.14 0)
			(effects
				(font
					(size 1.27 1.27)
				)
				(hide yes)
			)
		)
		(property "Description" ""
			(at 63.5 231.14 0)
			(effects
				(font
					(size 1.27 1.27)
				)
				(hide yes)
			)
		)
		(pin "1"
		)
		(instances
			(project "polarfire-som"
				(path ""
					(reference "#PWR0201")
					(unit 1)
				)
			)
		)
	)
	(symbol
		(lib_id "antmicroResistors0402:R_10k_0402")
		(at 92.71 200.66 90)
		(unit 1)
		(exclude_from_sim no)
		(in_bom yes)
		(on_board yes)
		(dnp no)
		(fields_autoplaced yes)
		(property "Reference" "R51"
			(at 94.615 196.8499 90)
			(effects
				(font
					(size 1.27 1.27)
					(thickness 0.15)
				)
				(justify right)
			)
		)
		(property "Value" "R_10k_0402"
			(at 105.41 180.34 0)
			(effects
				(font
					(size 1.27 1.27)
					(thickness 0.15)
				)
				(justify left bottom)
				(hide yes)
			)
		)
		(property "Footprint" "antmicro-footprints:R_0402_1005Metric"
			(at 107.95 180.34 0)
			(effects
				(font
					(size 1.27 1.27)
					(thickness 0.15)
				)
				(justify left bottom)
				(hide yes)
			)
		)
		(property "Datasheet" "https://www.bourns.com/docs/product-datasheets/cr.pdf"
			(at 110.49 180.34 0)
			(effects
				(font
					(size 1.27 1.27)
					(thickness 0.15)
				)
				(justify left bottom)
				(hide yes)
			)
		)
		(property "Description" "SMD Chip Resistor, 10 kohm, ± 1%, 62.5 mW, 0402 [1005 Metric], Thick Film, General Purpose"
			(at 92.71 200.66 0)
			(effects
				(font
					(size 1.27 1.27)
				)
				(hide yes)
			)
		)
		(property "MPN" "CR0402-FX-1002GLF"
			(at 113.03 180.34 0)
			(effects
				(font
					(size 1.27 1.27)
					(thickness 0.15)
				)
				(justify left bottom)
				(hide yes)
			)
		)
		(property "Manufacturer" "Bourns"
			(at 115.57 180.34 0)
			(effects
				(font
					(size 1.27 1.27)
					(thickness 0.15)
				)
				(justify left bottom)
				(hide yes)
			)
		)
		(property "License" "Apache-2.0"
			(at 118.11 180.34 0)
			(effects
				(font
					(size 1.27 1.27)
					(thickness 0.15)
				)
				(justify left bottom)
				(hide yes)
			)
		)
		(property "Author" "Antmicro"
			(at 120.65 180.34 0)
			(effects
				(font
					(size 1.27 1.27)
					(thickness 0.15)
				)
				(justify left bottom)
				(hide yes)
			)
		)
		(property "Val" "10k"
			(at 94.615 199.3899 90)
			(effects
				(font
					(size 1.27 1.27)
					(thickness 0.15)
				)
				(justify right)
			)
		)
		(property "Tolerance" "1%"
			(at 102.87 180.34 0)
			(effects
				(font
					(size 1.27 1.27)
				)
				(justify left bottom)
				(hide yes)
			)
		)
		(property "Public" ""
			(at 123.19 180.34 0)
			(effects
				(font
					(size 1.27 1.27)
				)
				(justify left bottom)
				(hide yes)
			)
		)
		(pin "1"
		)
		(pin "2"
		)
		(instances
			(project "polarfire-som"
				(path ""
					(reference "R51")
					(unit 1)
				)
			)
		)
	)
	(symbol
		(lib_id "antmicroResistors0402:R_10k_0402")
		(at 203.2 80.01 90)
		(unit 1)
		(exclude_from_sim no)
		(in_bom yes)
		(on_board yes)
		(dnp no)
		(property "Reference" "R28"
			(at 201.93 74.93 0)
			(effects
				(font
					(size 1.27 1.27)
					(thickness 0.15)
				)
				(justify left)
			)
		)
		(property "Value" "R_10k_0402"
			(at 215.9 59.69 0)
			(effects
				(font
					(size 1.27 1.27)
					(thickness 0.15)
				)
				(justify left bottom)
				(hide yes)
			)
		)
		(property "Footprint" "antmicro-footprints:R_0402_1005Metric"
			(at 218.44 59.69 0)
			(effects
				(font
					(size 1.27 1.27)
					(thickness 0.15)
				)
				(justify left bottom)
				(hide yes)
			)
		)
		(property "Datasheet" "https://www.bourns.com/docs/product-datasheets/cr.pdf"
			(at 220.98 59.69 0)
			(effects
				(font
					(size 1.27 1.27)
					(thickness 0.15)
				)
				(justify left bottom)
				(hide yes)
			)
		)
		(property "Description" "SMD Chip Resistor, 10 kohm, ± 1%, 62.5 mW, 0402 [1005 Metric], Thick Film, General Purpose"
			(at 203.2 80.01 0)
			(effects
				(font
					(size 1.27 1.27)
				)
				(hide yes)
			)
		)
		(property "MPN" "CR0402-FX-1002GLF"
			(at 223.52 59.69 0)
			(effects
				(font
					(size 1.27 1.27)
					(thickness 0.15)
				)
				(justify left bottom)
				(hide yes)
			)
		)
		(property "Manufacturer" "Bourns"
			(at 226.06 59.69 0)
			(effects
				(font
					(size 1.27 1.27)
					(thickness 0.15)
				)
				(justify left bottom)
				(hide yes)
			)
		)
		(property "License" "Apache-2.0"
			(at 228.6 59.69 0)
			(effects
				(font
					(size 1.27 1.27)
					(thickness 0.15)
				)
				(justify left bottom)
				(hide yes)
			)
		)
		(property "Author" "Antmicro"
			(at 231.14 59.69 0)
			(effects
				(font
					(size 1.27 1.27)
					(thickness 0.15)
				)
				(justify left bottom)
				(hide yes)
			)
		)
		(property "Val" "10k"
			(at 201.93 80.01 0)
			(effects
				(font
					(size 1.27 1.27)
					(thickness 0.15)
				)
				(justify right)
			)
		)
		(property "Tolerance" "1%"
			(at 213.36 59.69 0)
			(effects
				(font
					(size 1.27 1.27)
				)
				(justify left bottom)
				(hide yes)
			)
		)
		(property "Public" ""
			(at 233.68 59.69 0)
			(effects
				(font
					(size 1.27 1.27)
				)
				(justify left bottom)
				(hide yes)
			)
		)
		(pin "1"
		)
		(pin "2"
		)
		(instances
			(project "polarfire-som"
				(path ""
					(reference "R28")
					(unit 1)
				)
			)
		)
	)
	(symbol
		(lib_id "antmicroResistors0402:R_10k_0402")
		(at 128.27 219.71 90)
		(unit 1)
		(exclude_from_sim no)
		(in_bom yes)
		(on_board yes)
		(dnp yes)
		(property "Reference" "R55"
			(at 130.175 215.8999 90)
			(effects
				(font
					(size 1.27 1.27)
					(thickness 0.15)
				)
				(justify right)
			)
		)
		(property "Value" "R_10k_0402"
			(at 140.97 199.39 0)
			(effects
				(font
					(size 1.27 1.27)
					(thickness 0.15)
				)
				(justify left bottom)
				(hide yes)
			)
		)
		(property "Footprint" "antmicro-footprints:R_0402_1005Metric"
			(at 143.51 199.39 0)
			(effects
				(font
					(size 1.27 1.27)
					(thickness 0.15)
				)
				(justify left bottom)
				(hide yes)
			)
		)
		(property "Datasheet" "https://www.bourns.com/docs/product-datasheets/cr.pdf"
			(at 146.05 199.39 0)
			(effects
				(font
					(size 1.27 1.27)
					(thickness 0.15)
				)
				(justify left bottom)
				(hide yes)
			)
		)
		(property "Description" "SMD Chip Resistor, 10 kohm, ± 1%, 62.5 mW, 0402 [1005 Metric], Thick Film, General Purpose"
			(at 128.27 219.71 0)
			(effects
				(font
					(size 1.27 1.27)
				)
				(hide yes)
			)
		)
		(property "MPN" "CR0402-FX-1002GLF"
			(at 148.59 199.39 0)
			(effects
				(font
					(size 1.27 1.27)
					(thickness 0.15)
				)
				(justify left bottom)
				(hide yes)
			)
		)
		(property "Manufacturer" "Bourns"
			(at 151.13 199.39 0)
			(effects
				(font
					(size 1.27 1.27)
					(thickness 0.15)
				)
				(justify left bottom)
				(hide yes)
			)
		)
		(property "License" "Apache-2.0"
			(at 153.67 199.39 0)
			(effects
				(font
					(size 1.27 1.27)
					(thickness 0.15)
				)
				(justify left bottom)
				(hide yes)
			)
		)
		(property "Author" "Antmicro"
			(at 156.21 199.39 0)
			(effects
				(font
					(size 1.27 1.27)
					(thickness 0.15)
				)
				(justify left bottom)
				(hide yes)
			)
		)
		(property "Val" "10k"
			(at 130.175 218.4399 90)
			(effects
				(font
					(size 1.27 1.27)
					(thickness 0.15)
				)
				(justify right)
			)
		)
		(property "Tolerance" "1%"
			(at 138.43 199.39 0)
			(effects
				(font
					(size 1.27 1.27)
				)
				(justify left bottom)
				(hide yes)
			)
		)
		(property "DNP" "DNP"
			(at 128.27 217.17 0)
			(effects
				(font
					(size 1.27 1.27)
				)
				(hide yes)
			)
		)
		(property "Public" ""
			(at 158.75 199.39 0)
			(effects
				(font
					(size 1.27 1.27)
				)
				(justify left bottom)
				(hide yes)
			)
		)
		(pin "1"
		)
		(pin "2"
		)
		(instances
			(project "polarfire-som"
				(path ""
					(reference "R55")
					(unit 1)
				)
			)
		)
	)
	(symbol
		(lib_id "antmicroResistors0402:R_49k9_0402")
		(at 252.73 82.55 90)
		(unit 1)
		(exclude_from_sim no)
		(in_bom yes)
		(on_board yes)
		(dnp no)
		(property "Reference" "R37"
			(at 251.46 73.66 0)
			(effects
				(font
					(size 1.27 1.27)
					(thickness 0.15)
				)
				(justify right)
			)
		)
		(property "Value" "R_49k9_0402"
			(at 265.43 62.23 0)
			(effects
				(font
					(size 1.27 1.27)
					(thickness 0.15)
				)
				(justify left bottom)
				(hide yes)
			)
		)
		(property "Footprint" "antmicro-footprints:R_0402_1005Metric"
			(at 267.97 62.23 0)
			(effects
				(font
					(size 1.27 1.27)
					(thickness 0.15)
				)
				(justify left bottom)
				(hide yes)
			)
		)
		(property "Datasheet" "https://www.bourns.com/docs/product-datasheets/cr.pdf"
			(at 270.51 62.23 0)
			(effects
				(font
					(size 1.27 1.27)
					(thickness 0.15)
				)
				(justify left bottom)
				(hide yes)
			)
		)
		(property "Description" "SMD Chip Resistor, 49.9 kohm, ± 1%, 63 mW, 0402 [1005 Metric], Thick Film, General Purpose"
			(at 252.73 82.55 0)
			(effects
				(font
					(size 1.27 1.27)
				)
				(hide yes)
			)
		)
		(property "MPN" "CR0402-FX-4992GLF"
			(at 273.05 62.23 0)
			(effects
				(font
					(size 1.27 1.27)
					(thickness 0.15)
				)
				(justify left bottom)
				(hide yes)
			)
		)
		(property "Manufacturer" "Bourns"
			(at 275.59 62.23 0)
			(effects
				(font
					(size 1.27 1.27)
					(thickness 0.15)
				)
				(justify left bottom)
				(hide yes)
			)
		)
		(property "License" "Apache-2.0"
			(at 278.13 62.23 0)
			(effects
				(font
					(size 1.27 1.27)
					(thickness 0.15)
				)
				(justify left bottom)
				(hide yes)
			)
		)
		(property "Author" "Antmicro"
			(at 280.67 62.23 0)
			(effects
				(font
					(size 1.27 1.27)
					(thickness 0.15)
				)
				(justify left bottom)
				(hide yes)
			)
		)
		(property "Val" "49k9"
			(at 251.46 82.55 0)
			(effects
				(font
					(size 1.27 1.27)
					(thickness 0.15)
				)
				(justify right)
			)
		)
		(property "Tolerance" "1%"
			(at 262.89 62.23 0)
			(effects
				(font
					(size 1.27 1.27)
				)
				(justify left bottom)
				(hide yes)
			)
		)
		(property "Public" ""
			(at 283.21 62.23 0)
			(effects
				(font
					(size 1.27 1.27)
				)
				(justify left bottom)
				(hide yes)
			)
		)
		(pin "1"
		)
		(pin "2"
		)
		(instances
			(project "polarfire-som"
				(path ""
					(reference "R37")
					(unit 1)
				)
			)
		)
	)
	(symbol
		(lib_id "antmicropower:+3V3")
		(at 31.75 205.74 0)
		(unit 1)
		(exclude_from_sim no)
		(in_bom yes)
		(on_board yes)
		(dnp no)
		(property "Reference" "#PWR0186"
			(at 46.99 208.28 0)
			(effects
				(font
					(size 1.27 1.27)
					(thickness 0.15)
				)
				(justify left bottom)
				(hide yes)
			)
		)
		(property "Value" "+3V3"
			(at 31.75 201.93 0)
			(effects
				(font
					(size 1.27 1.27)
					(thickness 0.15)
				)
			)
		)
		(property "Footprint" ""
			(at 46.99 213.36 0)
			(effects
				(font
					(size 1.27 1.27)
					(thickness 0.15)
				)
				(justify left bottom)
				(hide yes)
			)
		)
		(property "Datasheet" ""
			(at 46.99 215.9 0)
			(effects
				(font
					(size 1.27 1.27)
					(thickness 0.15)
				)
				(justify left bottom)
				(hide yes)
			)
		)
		(property "Description" ""
			(at 31.75 205.74 0)
			(effects
				(font
					(size 1.27 1.27)
				)
				(hide yes)
			)
		)
		(property "Author" "Antmicro"
			(at 46.99 213.36 0)
			(effects
				(font
					(size 1.27 1.27)
					(thickness 0.15)
				)
				(justify left bottom)
				(hide yes)
			)
		)
		(property "License" "Apache-2.0"
			(at 46.99 215.9 0)
			(effects
				(font
					(size 1.27 1.27)
					(thickness 0.15)
				)
				(justify left bottom)
				(hide yes)
			)
		)
		(pin "1"
		)
		(instances
			(project "polarfire-som"
				(path ""
					(reference "#PWR0186")
					(unit 1)
				)
			)
		)
	)
	(symbol
		(lib_id "antmicropower:GND")
		(at 175.26 76.2 0)
		(unit 1)
		(exclude_from_sim no)
		(in_bom yes)
		(on_board yes)
		(dnp no)
		(fields_autoplaced yes)
		(property "Reference" "#PWR049"
			(at 184.15 78.74 0)
			(effects
				(font
					(size 1.27 1.27)
					(thickness 0.15)
				)
				(justify left bottom)
				(hide yes)
			)
		)
		(property "Value" "GND"
			(at 175.26 81.28 0)
			(effects
				(font
					(size 1.27 1.27)
					(thickness 0.15)
				)
			)
		)
		(property "Footprint" ""
			(at 184.15 83.82 0)
			(effects
				(font
					(size 1.27 1.27)
					(thickness 0.15)
				)
				(justify left bottom)
				(hide yes)
			)
		)
		(property "Datasheet" ""
			(at 184.15 88.9 0)
			(effects
				(font
					(size 1.27 1.27)
					(thickness 0.15)
				)
				(justify left bottom)
				(hide yes)
			)
		)
		(property "Description" ""
			(at 175.26 76.2 0)
			(effects
				(font
					(size 1.27 1.27)
				)
				(hide yes)
			)
		)
		(property "Author" "Antmicro"
			(at 184.15 83.82 0)
			(effects
				(font
					(size 1.27 1.27)
					(thickness 0.15)
				)
				(justify left bottom)
				(hide yes)
			)
		)
		(property "License" "Apache-2.0"
			(at 184.15 86.36 0)
			(effects
				(font
					(size 1.27 1.27)
					(thickness 0.15)
				)
				(justify left bottom)
				(hide yes)
			)
		)
		(pin "1"
		)
		(instances
			(project "polarfire-som"
				(path ""
					(reference "#PWR049")
					(unit 1)
				)
			)
		)
	)
	(symbol
		(lib_id "antmicroCapacitors0402:C_100n_0402")
		(at 158.75 127 90)
		(unit 1)
		(exclude_from_sim no)
		(in_bom yes)
		(on_board yes)
		(dnp no)
		(property "Reference" "C78"
			(at 158.75 121.92 90)
			(effects
				(font
					(size 1.27 1.27)
					(thickness 0.15)
				)
				(justify right)
			)
		)
		(property "Value" "C_100n_0402"
			(at 168.91 106.68 0)
			(effects
				(font
					(size 1.27 1.27)
					(thickness 0.15)
				)
				(justify left bottom)
				(hide yes)
			)
		)
		(property "Footprint" "antmicro-footprints:C_0402_1005Metric"
			(at 171.45 106.68 0)
			(effects
				(font
					(size 1.27 1.27)
					(thickness 0.15)
				)
				(justify left bottom)
				(hide yes)
			)
		)
		(property "Datasheet" "https://www.murata.com/products/productdetail?partno=GRM155R61H104KE14%23"
			(at 173.99 106.68 0)
			(effects
				(font
					(size 1.27 1.27)
					(thickness 0.15)
				)
				(justify left bottom)
				(hide yes)
			)
		)
		(property "Description" "SMD Multilayer Ceramic Capacitor, 0.1 µF, 50 V, 0402 [1005 Metric], ± 10%, X5R, GRM Series"
			(at 158.75 127 0)
			(effects
				(font
					(size 1.27 1.27)
				)
				(hide yes)
			)
		)
		(property "MPN" "GRM155R61H104KE14D"
			(at 176.53 106.68 0)
			(effects
				(font
					(size 1.27 1.27)
					(thickness 0.15)
				)
				(justify left bottom)
				(hide yes)
			)
		)
		(property "Manufacturer" "Murata"
			(at 179.07 106.68 0)
			(effects
				(font
					(size 1.27 1.27)
					(thickness 0.15)
				)
				(justify left bottom)
				(hide yes)
			)
		)
		(property "License" "Apache-2.0"
			(at 181.61 106.68 0)
			(effects
				(font
					(size 1.27 1.27)
					(thickness 0.15)
				)
				(justify left bottom)
				(hide yes)
			)
		)
		(property "Author" "Antmicro"
			(at 184.15 106.68 0)
			(effects
				(font
					(size 1.27 1.27)
					(thickness 0.15)
				)
				(justify left bottom)
				(hide yes)
			)
		)
		(property "Val" "100n"
			(at 158.75 127 90)
			(effects
				(font
					(size 1.27 1.27)
					(thickness 0.15)
				)
				(justify right)
			)
		)
		(property "Voltage" "50V"
			(at 186.69 106.68 0)
			(effects
				(font
					(size 1.27 1.27)
				)
				(justify left bottom)
				(hide yes)
			)
		)
		(property "Dielectric" "X5R"
			(at 189.23 106.68 0)
			(effects
				(font
					(size 1.27 1.27)
				)
				(justify left bottom)
				(hide yes)
			)
		)
		(property "Public" ""
			(at 191.77 106.68 0)
			(effects
				(font
					(size 1.27 1.27)
				)
				(justify left bottom)
				(hide yes)
			)
		)
		(pin "1"
		)
		(pin "2"
		)
		(instances
			(project "polarfire-som"
				(path ""
					(reference "C78")
					(unit 1)
				)
			)
		)
	)
	(symbol
		(lib_id "antmicroCapacitors0402:C_100n_0402")
		(at 175.26 72.39 90)
		(unit 1)
		(exclude_from_sim no)
		(in_bom yes)
		(on_board yes)
		(dnp no)
		(property "Reference" "C70"
			(at 177.8 68.5735 90)
			(effects
				(font
					(size 1.27 1.27)
					(thickness 0.15)
				)
				(justify right)
			)
		)
		(property "Value" "C_100n_0402"
			(at 185.42 52.07 0)
			(effects
				(font
					(size 1.27 1.27)
					(thickness 0.15)
				)
				(justify left bottom)
				(hide yes)
			)
		)
		(property "Footprint" "antmicro-footprints:C_0402_1005Metric"
			(at 187.96 52.07 0)
			(effects
				(font
					(size 1.27 1.27)
					(thickness 0.15)
				)
				(justify left bottom)
				(hide yes)
			)
		)
		(property "Datasheet" "https://www.murata.com/products/productdetail?partno=GRM155R61H104KE14%23"
			(at 190.5 52.07 0)
			(effects
				(font
					(size 1.27 1.27)
					(thickness 0.15)
				)
				(justify left bottom)
				(hide yes)
			)
		)
		(property "Description" "SMD Multilayer Ceramic Capacitor, 0.1 µF, 50 V, 0402 [1005 Metric], ± 10%, X5R, GRM Series"
			(at 175.26 72.39 0)
			(effects
				(font
					(size 1.27 1.27)
				)
				(hide yes)
			)
		)
		(property "MPN" "GRM155R61H104KE14D"
			(at 193.04 52.07 0)
			(effects
				(font
					(size 1.27 1.27)
					(thickness 0.15)
				)
				(justify left bottom)
				(hide yes)
			)
		)
		(property "Manufacturer" "Murata"
			(at 195.58 52.07 0)
			(effects
				(font
					(size 1.27 1.27)
					(thickness 0.15)
				)
				(justify left bottom)
				(hide yes)
			)
		)
		(property "License" "Apache-2.0"
			(at 198.12 52.07 0)
			(effects
				(font
					(size 1.27 1.27)
					(thickness 0.15)
				)
				(justify left bottom)
				(hide yes)
			)
		)
		(property "Author" "Antmicro"
			(at 200.66 52.07 0)
			(effects
				(font
					(size 1.27 1.27)
					(thickness 0.15)
				)
				(justify left bottom)
				(hide yes)
			)
		)
		(property "Val" "100n"
			(at 182.88 70.485 90)
			(effects
				(font
					(size 1.27 1.27)
					(thickness 0.15)
				)
				(justify left bottom)
			)
		)
		(property "Voltage" "50V"
			(at 203.2 52.07 0)
			(effects
				(font
					(size 1.27 1.27)
				)
				(justify left bottom)
				(hide yes)
			)
		)
		(property "Dielectric" "X5R"
			(at 205.74 52.07 0)
			(effects
				(font
					(size 1.27 1.27)
				)
				(justify left bottom)
				(hide yes)
			)
		)
		(property "Public" ""
			(at 208.28 52.07 0)
			(effects
				(font
					(size 1.27 1.27)
				)
				(justify left bottom)
				(hide yes)
			)
		)
		(pin "1"
		)
		(pin "2"
		)
		(instances
			(project "polarfire-som"
				(path ""
					(reference "C70")
					(unit 1)
				)
			)
		)
	)
	(symbol
		(lib_id "antmicropower:GND")
		(at 142.24 132.08 0)
		(unit 1)
		(exclude_from_sim no)
		(in_bom yes)
		(on_board yes)
		(dnp no)
		(fields_autoplaced yes)
		(property "Reference" "#PWR047"
			(at 151.13 134.62 0)
			(effects
				(font
					(size 1.27 1.27)
					(thickness 0.15)
				)
				(justify left bottom)
				(hide yes)
			)
		)
		(property "Value" "GND"
			(at 142.24 137.16 0)
			(effects
				(font
					(size 1.27 1.27)
					(thickness 0.15)
				)
			)
		)
		(property "Footprint" ""
			(at 151.13 139.7 0)
			(effects
				(font
					(size 1.27 1.27)
					(thickness 0.15)
				)
				(justify left bottom)
				(hide yes)
			)
		)
		(property "Datasheet" ""
			(at 151.13 144.78 0)
			(effects
				(font
					(size 1.27 1.27)
					(thickness 0.15)
				)
				(justify left bottom)
				(hide yes)
			)
		)
		(property "Description" ""
			(at 142.24 132.08 0)
			(effects
				(font
					(size 1.27 1.27)
				)
				(hide yes)
			)
		)
		(property "Author" "Antmicro"
			(at 151.13 139.7 0)
			(effects
				(font
					(size 1.27 1.27)
					(thickness 0.15)
				)
				(justify left bottom)
				(hide yes)
			)
		)
		(property "License" "Apache-2.0"
			(at 151.13 142.24 0)
			(effects
				(font
					(size 1.27 1.27)
					(thickness 0.15)
				)
				(justify left bottom)
				(hide yes)
			)
		)
		(pin "1"
		)
		(instances
			(project "polarfire-som"
				(path ""
					(reference "#PWR047")
					(unit 1)
				)
			)
		)
	)
	(symbol
		(lib_id "antmicroResistors0402:R_0R_0402")
		(at 85.09 199.39 90)
		(unit 1)
		(exclude_from_sim no)
		(in_bom yes)
		(on_board yes)
		(dnp no)
		(fields_autoplaced yes)
		(property "Reference" "R50"
			(at 86.995 195.5799 90)
			(effects
				(font
					(size 1.27 1.27)
					(thickness 0.15)
				)
				(justify right)
			)
		)
		(property "Value" "R_0R_0402"
			(at 97.79 179.07 0)
			(effects
				(font
					(size 1.27 1.27)
					(thickness 0.15)
				)
				(justify left bottom)
				(hide yes)
			)
		)
		(property "Footprint" "antmicro-footprints:R_0402_1005Metric"
			(at 100.33 179.07 0)
			(effects
				(font
					(size 1.27 1.27)
					(thickness 0.15)
				)
				(justify left bottom)
				(hide yes)
			)
		)
		(property "Datasheet" "https://industrial.panasonic.com/cdbs/www-data/pdf/RDA0000/AOA0000C301.pdf"
			(at 102.87 179.07 0)
			(effects
				(font
					(size 1.27 1.27)
					(thickness 0.15)
				)
				(justify left bottom)
				(hide yes)
			)
		)
		(property "Description" "SMD Chip Resistor, Jumper, 0 ohm, 100 mW, 0402 [1005 Metric], Thick Film, General Purpose"
			(at 85.09 199.39 0)
			(effects
				(font
					(size 1.27 1.27)
				)
				(hide yes)
			)
		)
		(property "MPN" "ERJ2GE0R00X"
			(at 105.41 179.07 0)
			(effects
				(font
					(size 1.27 1.27)
					(thickness 0.15)
				)
				(justify left bottom)
				(hide yes)
			)
		)
		(property "Manufacturer" "Panasonic"
			(at 107.95 179.07 0)
			(effects
				(font
					(size 1.27 1.27)
					(thickness 0.15)
				)
				(justify left bottom)
				(hide yes)
			)
		)
		(property "License" "Apache-2.0"
			(at 110.49 179.07 0)
			(effects
				(font
					(size 1.27 1.27)
					(thickness 0.15)
				)
				(justify left bottom)
				(hide yes)
			)
		)
		(property "Author" "Antmicro"
			(at 113.03 179.07 0)
			(effects
				(font
					(size 1.27 1.27)
					(thickness 0.15)
				)
				(justify left bottom)
				(hide yes)
			)
		)
		(property "Val" "0R"
			(at 86.995 198.1199 90)
			(effects
				(font
					(size 1.27 1.27)
					(thickness 0.15)
				)
				(justify right)
			)
		)
		(property "Tolerance" "~"
			(at 95.25 179.07 0)
			(effects
				(font
					(size 1.27 1.27)
				)
				(justify left bottom)
				(hide yes)
			)
		)
		(property "Current" "1A"
			(at 115.57 179.07 0)
			(effects
				(font
					(size 1.27 1.27)
					(thickness 0.15)
				)
				(justify left bottom)
				(hide yes)
			)
		)
		(property "Public" ""
			(at 115.57 179.07 0)
			(effects
				(font
					(size 1.27 1.27)
				)
				(justify left bottom)
				(hide yes)
			)
		)
		(pin "1"
		)
		(pin "2"
		)
		(instances
			(project "polarfire-som"
				(path ""
					(reference "R50")
					(unit 1)
				)
			)
		)
	)
	(symbol
		(lib_id "antmicroResistors0402:R_10k_0402")
		(at 57.15 209.55 270)
		(unit 1)
		(exclude_from_sim no)
		(in_bom yes)
		(on_board yes)
		(dnp no)
		(fields_autoplaced yes)
		(property "Reference" "R52"
			(at 55.245 213.3601 90)
			(effects
				(font
					(size 1.27 1.27)
					(thickness 0.15)
				)
				(justify right)
			)
		)
		(property "Value" "R_10k_0402"
			(at 44.45 229.87 0)
			(effects
				(font
					(size 1.27 1.27)
					(thickness 0.15)
				)
				(justify left bottom)
				(hide yes)
			)
		)
		(property "Footprint" "antmicro-footprints:R_0402_1005Metric"
			(at 41.91 229.87 0)
			(effects
				(font
					(size 1.27 1.27)
					(thickness 0.15)
				)
				(justify left bottom)
				(hide yes)
			)
		)
		(property "Datasheet" "https://www.bourns.com/docs/product-datasheets/cr.pdf"
			(at 39.37 229.87 0)
			(effects
				(font
					(size 1.27 1.27)
					(thickness 0.15)
				)
				(justify left bottom)
				(hide yes)
			)
		)
		(property "Description" "SMD Chip Resistor, 10 kohm, ± 1%, 62.5 mW, 0402 [1005 Metric], Thick Film, General Purpose"
			(at 57.15 209.55 0)
			(effects
				(font
					(size 1.27 1.27)
				)
				(hide yes)
			)
		)
		(property "MPN" "CR0402-FX-1002GLF"
			(at 36.83 229.87 0)
			(effects
				(font
					(size 1.27 1.27)
					(thickness 0.15)
				)
				(justify left bottom)
				(hide yes)
			)
		)
		(property "Manufacturer" "Bourns"
			(at 34.29 229.87 0)
			(effects
				(font
					(size 1.27 1.27)
					(thickness 0.15)
				)
				(justify left bottom)
				(hide yes)
			)
		)
		(property "License" "Apache-2.0"
			(at 31.75 229.87 0)
			(effects
				(font
					(size 1.27 1.27)
					(thickness 0.15)
				)
				(justify left bottom)
				(hide yes)
			)
		)
		(property "Author" "Antmicro"
			(at 29.21 229.87 0)
			(effects
				(font
					(size 1.27 1.27)
					(thickness 0.15)
				)
				(justify left bottom)
				(hide yes)
			)
		)
		(property "Val" "10k"
			(at 55.245 210.8201 90)
			(effects
				(font
					(size 1.27 1.27)
					(thickness 0.15)
				)
				(justify right)
			)
		)
		(property "Tolerance" "1%"
			(at 46.99 229.87 0)
			(effects
				(font
					(size 1.27 1.27)
				)
				(justify left bottom)
				(hide yes)
			)
		)
		(property "Public" ""
			(at 26.67 229.87 0)
			(effects
				(font
					(size 1.27 1.27)
				)
				(justify left bottom)
				(hide yes)
			)
		)
		(pin "1"
		)
		(pin "2"
		)
		(instances
			(project "polarfire-som"
				(path ""
					(reference "R52")
					(unit 1)
				)
			)
		)
	)
	(symbol
		(lib_id "antmicroMemory:SDINBDG4-8G")
		(at 304.8 67.31 0)
		(unit 2)
		(exclude_from_sim no)
		(in_bom yes)
		(on_board yes)
		(dnp no)
		(fields_autoplaced yes)
		(property "Reference" "U2"
			(at 322.58 104.775 0)
			(effects
				(font
					(size 1.27 1.27)
					(thickness 0.15)
				)
				(justify left)
			)
		)
		(property "Value" "SDINBDG4-8G"
			(at 342.9 74.93 0)
			(effects
				(font
					(size 1.27 1.27)
					(thickness 0.15)
				)
				(justify left bottom)
				(hide yes)
			)
		)
		(property "Footprint" "antmicro-footprints:BGA-196-153_11.5x13mm_Layout14x14_P0.5x0.5mm"
			(at 342.9 77.47 0)
			(effects
				(font
					(size 1.27 1.27)
					(thickness 0.15)
				)
				(justify left bottom)
				(hide yes)
			)
		)
		(property "Datasheet" "https://www.infineon.com/dgdl/Infineon-AN98491_Recommended_PCB_Routing_Guidelines_for_a_Infineon_e.MMC_Memory_Device-ApplicationNotes-v05_00-EN.pdf?fileId=8ac78c8c7d718a49017d71baea97084d"
			(at 342.9 80.01 0)
			(effects
				(font
					(size 1.27 1.27)
					(thickness 0.15)
				)
				(justify left bottom)
				(hide yes)
			)
		)
		(property "Description" "NAND Flash Serial e-MMC 64G-bit SanDisk iNAND 7250 Industrial emmc"
			(at 304.8 67.31 0)
			(effects
				(font
					(size 1.27 1.27)
				)
				(hide yes)
			)
		)
		(property "MPN" "SDINBDG4-8G"
			(at 322.58 107.315 0)
			(effects
				(font
					(size 1.27 1.27)
					(thickness 0.15)
				)
				(justify left)
			)
		)
		(property "Manufacturer" "SanDisk"
			(at 342.9 82.55 0)
			(effects
				(font
					(size 1.27 1.27)
					(thickness 0.15)
				)
				(justify left bottom)
				(hide yes)
			)
		)
		(property "Author" "Antmicro"
			(at 342.9 87.63 0)
			(effects
				(font
					(size 1.27 1.27)
					(thickness 0.15)
				)
				(justify left bottom)
				(hide yes)
			)
		)
		(property "License" "Apache-2.0"
			(at 342.9 90.17 0)
			(effects
				(font
					(size 1.27 1.27)
					(thickness 0.15)
				)
				(justify left bottom)
				(hide yes)
			)
		)
		(property "VSD_class" "eMMC"
			(at 342.9 85.09 0)
			(effects
				(font
					(size 1.27 1.27)
					(thickness 0.15)
				)
				(justify left bottom)
				(hide yes)
			)
		)
		(pin "N10"
		)
		(pin "N12"
		)
		(pin "B12"
		)
		(pin "P8"
		)
		(pin "A13"
		)
		(pin "E7"
		)
		(pin "E1"
		)
		(pin "J13"
		)
		(pin "C9"
		)
		(pin "H5"
		)
		(pin "P3"
		)
		(pin "H14"
		)
		(pin "P1"
		)
		(pin "J2"
		)
		(pin "J1"
		)
		(pin "B5"
		)
		(pin "A12"
		)
		(pin "F3"
		)
		(pin "H1"
		)
		(pin "E2"
		)
		(pin "C5"
		)
		(pin "G2"
		)
		(pin "K8"
		)
		(pin "M9"
		)
		(pin "B14"
		)
		(pin "F13"
		)
		(pin "A14"
		)
		(pin "E5"
		)
		(pin "K10"
		)
		(pin "F5"
		)
		(pin "J10"
		)
		(pin "G12"
		)
		(pin "P12"
		)
		(pin "G1"
		)
		(pin "K3"
		)
		(pin "L12"
		)
		(pin "E12"
		)
		(pin "B9"
		)
		(pin "F12"
		)
		(pin "E13"
		)
		(pin "A8"
		)
		(pin "G13"
		)
		(pin "P7"
		)
		(pin "M6"
		)
		(pin "K6"
		)
		(pin "J3"
		)
		(pin "M3"
		)
		(pin "B13"
		)
		(pin "A9"
		)
		(pin "C8"
		)
		(pin "L3"
		)
		(pin "A4"
		)
		(pin "N9"
		)
		(pin "P11"
		)
		(pin "L14"
		)
		(pin "L13"
		)
		(pin "N7"
		)
		(pin "P2"
		)
		(pin "K13"
		)
		(pin "D1"
		)
		(pin "H12"
		)
		(pin "M13"
		)
		(pin "D13"
		)
		(pin "J12"
		)
		(pin "E6"
		)
		(pin "N3"
		)
		(pin "C13"
		)
		(pin "A7"
		)
		(pin "M14"
		)
		(pin "P5"
		)
		(pin "C11"
		)
		(pin "J5"
		)
		(pin "D3"
		)
		(pin "M1"
		)
		(pin "J14"
		)
		(pin "E9"
		)
		(pin "B8"
		)
		(pin "E10"
		)
		(pin "C2"
		)
		(pin "N11"
		)
		(pin "N1"
		)
		(pin "P14"
		)
		(pin "A6"
		)
		(pin "G14"
		)
		(pin "G5"
		)
		(pin "F14"
		)
		(pin "C1"
		)
		(pin "B3"
		)
		(pin "A10"
		)
		(pin "K7"
		)
		(pin "H13"
		)
		(pin "G10"
		)
		(pin "H2"
		)
		(pin "K12"
		)
		(pin "P6"
		)
		(pin "L1"
		)
		(pin "A1"
		)
		(pin "P4"
		)
		(pin "P9"
		)
		(pin "F10"
		)
		(pin "M11"
		)
		(pin "K1"
		)
		(pin "G3"
		)
		(pin "M8"
		)
		(pin "C12"
		)
		(pin "N6"
		)
		(pin "N13"
		)
		(pin "H3"
		)
		(pin "E3"
		)
		(pin "M5"
		)
		(pin "B6"
		)
		(pin "N14"
		)
		(pin "A11"
		)
		(pin "E14"
		)
		(pin "F2"
		)
		(pin "A5"
		)
		(pin "K2"
		)
		(pin "D12"
		)
		(pin "H10"
		)
		(pin "B10"
		)
		(pin "D14"
		)
		(pin "L2"
		)
		(pin "C10"
		)
		(pin "M2"
		)
		(pin "K5"
		)
		(pin "N2"
		)
		(pin "E8"
		)
		(pin "N8"
		)
		(pin "K14"
		)
		(pin "P10"
		)
		(pin "B7"
		)
		(pin "A3"
		)
		(pin "M7"
		)
		(pin "P13"
		)
		(pin "B11"
		)
		(pin "A2"
		)
		(pin "C7"
		)
		(pin "C3"
		)
		(pin "B2"
		)
		(pin "M10"
		)
		(pin "B4"
		)
		(pin "M12"
		)
		(pin "D4"
		)
		(pin "C14"
		)
		(pin "D2"
		)
		(pin "C4"
		)
		(pin "N4"
		)
		(pin "N5"
		)
		(pin "M4"
		)
		(pin "C6"
		)
		(pin "B1"
		)
		(pin "F1"
		)
		(pin "K9"
		)
		(instances
			(project ""
				(path ""
					(reference "U2")
					(unit 2)
				)
			)
		)
	)
	(symbol
		(lib_id "antmicropower:GND")
		(at 86.36 241.3 0)
		(unit 1)
		(exclude_from_sim no)
		(in_bom yes)
		(on_board yes)
		(dnp no)
		(property "Reference" "#PWR0203"
			(at 95.25 243.84 0)
			(effects
				(font
					(size 1.27 1.27)
					(thickness 0.15)
				)
				(justify left bottom)
				(hide yes)
			)
		)
		(property "Value" "GND"
			(at 86.36 245.11 0)
			(effects
				(font
					(size 1.27 1.27)
					(thickness 0.15)
				)
			)
		)
		(property "Footprint" ""
			(at 95.25 248.92 0)
			(effects
				(font
					(size 1.27 1.27)
					(thickness 0.15)
				)
				(justify left bottom)
				(hide yes)
			)
		)
		(property "Datasheet" ""
			(at 95.25 254 0)
			(effects
				(font
					(size 1.27 1.27)
					(thickness 0.15)
				)
				(justify left bottom)
				(hide yes)
			)
		)
		(property "Description" ""
			(at 86.36 241.3 0)
			(effects
				(font
					(size 1.27 1.27)
				)
				(hide yes)
			)
		)
		(property "Author" "Antmicro"
			(at 95.25 248.92 0)
			(effects
				(font
					(size 1.27 1.27)
					(thickness 0.15)
				)
				(justify left bottom)
				(hide yes)
			)
		)
		(property "License" "Apache-2.0"
			(at 95.25 251.46 0)
			(effects
				(font
					(size 1.27 1.27)
					(thickness 0.15)
				)
				(justify left bottom)
				(hide yes)
			)
		)
		(pin "1"
		)
		(instances
			(project "polarfire-som"
				(path ""
					(reference "#PWR0203")
					(unit 1)
				)
			)
		)
	)
	(symbol
		(lib_id "antmicropower:GND")
		(at 57.15 215.9 0)
		(unit 1)
		(exclude_from_sim no)
		(in_bom yes)
		(on_board yes)
		(dnp no)
		(property "Reference" "#PWR0193"
			(at 66.04 218.44 0)
			(effects
				(font
					(size 1.27 1.27)
					(thickness 0.15)
				)
				(justify left bottom)
				(hide yes)
			)
		)
		(property "Value" "GND"
			(at 57.15 219.71 0)
			(effects
				(font
					(size 1.27 1.27)
					(thickness 0.15)
				)
			)
		)
		(property "Footprint" ""
			(at 66.04 223.52 0)
			(effects
				(font
					(size 1.27 1.27)
					(thickness 0.15)
				)
				(justify left bottom)
				(hide yes)
			)
		)
		(property "Datasheet" ""
			(at 66.04 228.6 0)
			(effects
				(font
					(size 1.27 1.27)
					(thickness 0.15)
				)
				(justify left bottom)
				(hide yes)
			)
		)
		(property "Description" ""
			(at 57.15 215.9 0)
			(effects
				(font
					(size 1.27 1.27)
				)
				(hide yes)
			)
		)
		(property "Author" "Antmicro"
			(at 66.04 223.52 0)
			(effects
				(font
					(size 1.27 1.27)
					(thickness 0.15)
				)
				(justify left bottom)
				(hide yes)
			)
		)
		(property "License" "Apache-2.0"
			(at 66.04 226.06 0)
			(effects
				(font
					(size 1.27 1.27)
					(thickness 0.15)
				)
				(justify left bottom)
				(hide yes)
			)
		)
		(pin "1"
		)
		(instances
			(project "polarfire-som"
				(path ""
					(reference "#PWR0193")
					(unit 1)
				)
			)
		)
	)
	(symbol
		(lib_id "antmicroResistors0402:R_49k9_0402")
		(at 245.11 82.55 90)
		(unit 1)
		(exclude_from_sim no)
		(in_bom yes)
		(on_board yes)
		(dnp no)
		(property "Reference" "R34"
			(at 243.84 73.66 0)
			(effects
				(font
					(size 1.27 1.27)
					(thickness 0.15)
				)
				(justify right)
			)
		)
		(property "Value" "R_49k9_0402"
			(at 257.81 62.23 0)
			(effects
				(font
					(size 1.27 1.27)
					(thickness 0.15)
				)
				(justify left bottom)
				(hide yes)
			)
		)
		(property "Footprint" "antmicro-footprints:R_0402_1005Metric"
			(at 260.35 62.23 0)
			(effects
				(font
					(size 1.27 1.27)
					(thickness 0.15)
				)
				(justify left bottom)
				(hide yes)
			)
		)
		(property "Datasheet" "https://www.bourns.com/docs/product-datasheets/cr.pdf"
			(at 262.89 62.23 0)
			(effects
				(font
					(size 1.27 1.27)
					(thickness 0.15)
				)
				(justify left bottom)
				(hide yes)
			)
		)
		(property "Description" "SMD Chip Resistor, 49.9 kohm, ± 1%, 63 mW, 0402 [1005 Metric], Thick Film, General Purpose"
			(at 245.11 82.55 0)
			(effects
				(font
					(size 1.27 1.27)
				)
				(hide yes)
			)
		)
		(property "MPN" "CR0402-FX-4992GLF"
			(at 265.43 62.23 0)
			(effects
				(font
					(size 1.27 1.27)
					(thickness 0.15)
				)
				(justify left bottom)
				(hide yes)
			)
		)
		(property "Manufacturer" "Bourns"
			(at 267.97 62.23 0)
			(effects
				(font
					(size 1.27 1.27)
					(thickness 0.15)
				)
				(justify left bottom)
				(hide yes)
			)
		)
		(property "License" "Apache-2.0"
			(at 270.51 62.23 0)
			(effects
				(font
					(size 1.27 1.27)
					(thickness 0.15)
				)
				(justify left bottom)
				(hide yes)
			)
		)
		(property "Author" "Antmicro"
			(at 273.05 62.23 0)
			(effects
				(font
					(size 1.27 1.27)
					(thickness 0.15)
				)
				(justify left bottom)
				(hide yes)
			)
		)
		(property "Val" "49k9"
			(at 243.84 82.55 0)
			(effects
				(font
					(size 1.27 1.27)
					(thickness 0.15)
				)
				(justify right)
			)
		)
		(property "Tolerance" "1%"
			(at 255.27 62.23 0)
			(effects
				(font
					(size 1.27 1.27)
				)
				(justify left bottom)
				(hide yes)
			)
		)
		(property "Public" ""
			(at 275.59 62.23 0)
			(effects
				(font
					(size 1.27 1.27)
				)
				(justify left bottom)
				(hide yes)
			)
		)
		(pin "1"
		)
		(pin "2"
		)
		(instances
			(project "polarfire-som"
				(path ""
					(reference "R34")
					(unit 1)
				)
			)
		)
	)
	(symbol
		(lib_id "antmicropower:VDDI")
		(at 92.71 194.31 0)
		(unit 1)
		(exclude_from_sim no)
		(in_bom yes)
		(on_board yes)
		(dnp no)
		(fields_autoplaced yes)
		(property "Reference" "#PWR0336"
			(at 92.71 198.12 0)
			(effects
				(font
					(size 1.27 1.27)
				)
				(hide yes)
			)
		)
		(property "Value" "VDD"
			(at 92.71 189.865 0)
			(effects
				(font
					(size 1.27 1.27)
				)
			)
		)
		(property "Footprint" ""
			(at 92.71 194.31 0)
			(effects
				(font
					(size 1.27 1.27)
				)
				(hide yes)
			)
		)
		(property "Datasheet" ""
			(at 92.71 194.31 0)
			(effects
				(font
					(size 1.27 1.27)
				)
				(hide yes)
			)
		)
		(property "Description" ""
			(at 92.71 194.31 0)
			(effects
				(font
					(size 1.27 1.27)
				)
				(hide yes)
			)
		)
		(pin "1"
		)
		(instances
			(project "polarfire-som"
				(path ""
					(reference "#PWR0336")
					(unit 1)
				)
			)
		)
	)
	(symbol
		(lib_id "antmicroCapacitors0402:C_100n_0402")
		(at 157.48 72.39 90)
		(unit 1)
		(exclude_from_sim no)
		(in_bom yes)
		(on_board yes)
		(dnp no)
		(property "Reference" "C72"
			(at 157.48 67.31 90)
			(effects
				(font
					(size 1.27 1.27)
					(thickness 0.15)
				)
				(justify right)
			)
		)
		(property "Value" "C_100n_0402"
			(at 167.64 52.07 0)
			(effects
				(font
					(size 1.27 1.27)
					(thickness 0.15)
				)
				(justify left bottom)
				(hide yes)
			)
		)
		(property "Footprint" "antmicro-footprints:C_0402_1005Metric"
			(at 170.18 52.07 0)
			(effects
				(font
					(size 1.27 1.27)
					(thickness 0.15)
				)
				(justify left bottom)
				(hide yes)
			)
		)
		(property "Datasheet" "https://www.murata.com/products/productdetail?partno=GRM155R61H104KE14%23"
			(at 172.72 52.07 0)
			(effects
				(font
					(size 1.27 1.27)
					(thickness 0.15)
				)
				(justify left bottom)
				(hide yes)
			)
		)
		(property "Description" "SMD Multilayer Ceramic Capacitor, 0.1 µF, 50 V, 0402 [1005 Metric], ± 10%, X5R, GRM Series"
			(at 157.48 72.39 0)
			(effects
				(font
					(size 1.27 1.27)
				)
				(hide yes)
			)
		)
		(property "MPN" "GRM155R61H104KE14D"
			(at 175.26 52.07 0)
			(effects
				(font
					(size 1.27 1.27)
					(thickness 0.15)
				)
				(justify left bottom)
				(hide yes)
			)
		)
		(property "Manufacturer" "Murata"
			(at 177.8 52.07 0)
			(effects
				(font
					(size 1.27 1.27)
					(thickness 0.15)
				)
				(justify left bottom)
				(hide yes)
			)
		)
		(property "License" "Apache-2.0"
			(at 180.34 52.07 0)
			(effects
				(font
					(size 1.27 1.27)
					(thickness 0.15)
				)
				(justify left bottom)
				(hide yes)
			)
		)
		(property "Author" "Antmicro"
			(at 182.88 52.07 0)
			(effects
				(font
					(size 1.27 1.27)
					(thickness 0.15)
				)
				(justify left bottom)
				(hide yes)
			)
		)
		(property "Val" "100n"
			(at 157.48 72.39 90)
			(effects
				(font
					(size 1.27 1.27)
					(thickness 0.15)
				)
				(justify right)
			)
		)
		(property "Voltage" "50V"
			(at 185.42 52.07 0)
			(effects
				(font
					(size 1.27 1.27)
				)
				(justify left bottom)
				(hide yes)
			)
		)
		(property "Dielectric" "X5R"
			(at 187.96 52.07 0)
			(effects
				(font
					(size 1.27 1.27)
				)
				(justify left bottom)
				(hide yes)
			)
		)
		(property "Public" ""
			(at 190.5 52.07 0)
			(effects
				(font
					(size 1.27 1.27)
				)
				(justify left bottom)
				(hide yes)
			)
		)
		(pin "1"
		)
		(pin "2"
		)
		(instances
			(project "polarfire-som"
				(path ""
					(reference "C72")
					(unit 1)
				)
			)
		)
	)
	(symbol
		(lib_id "antmicroCapacitors0402:C_100n_0402")
		(at 163.83 72.39 90)
		(unit 1)
		(exclude_from_sim no)
		(in_bom yes)
		(on_board yes)
		(dnp no)
		(property "Reference" "C73"
			(at 163.83 67.31 90)
			(effects
				(font
					(size 1.27 1.27)
					(thickness 0.15)
				)
				(justify right)
			)
		)
		(property "Value" "C_100n_0402"
			(at 173.99 52.07 0)
			(effects
				(font
					(size 1.27 1.27)
					(thickness 0.15)
				)
				(justify left bottom)
				(hide yes)
			)
		)
		(property "Footprint" "antmicro-footprints:C_0402_1005Metric"
			(at 176.53 52.07 0)
			(effects
				(font
					(size 1.27 1.27)
					(thickness 0.15)
				)
				(justify left bottom)
				(hide yes)
			)
		)
		(property "Datasheet" "https://www.murata.com/products/productdetail?partno=GRM155R61H104KE14%23"
			(at 179.07 52.07 0)
			(effects
				(font
					(size 1.27 1.27)
					(thickness 0.15)
				)
				(justify left bottom)
				(hide yes)
			)
		)
		(property "Description" "SMD Multilayer Ceramic Capacitor, 0.1 µF, 50 V, 0402 [1005 Metric], ± 10%, X5R, GRM Series"
			(at 163.83 72.39 0)
			(effects
				(font
					(size 1.27 1.27)
				)
				(hide yes)
			)
		)
		(property "MPN" "GRM155R61H104KE14D"
			(at 181.61 52.07 0)
			(effects
				(font
					(size 1.27 1.27)
					(thickness 0.15)
				)
				(justify left bottom)
				(hide yes)
			)
		)
		(property "Manufacturer" "Murata"
			(at 184.15 52.07 0)
			(effects
				(font
					(size 1.27 1.27)
					(thickness 0.15)
				)
				(justify left bottom)
				(hide yes)
			)
		)
		(property "License" "Apache-2.0"
			(at 186.69 52.07 0)
			(effects
				(font
					(size 1.27 1.27)
					(thickness 0.15)
				)
				(justify left bottom)
				(hide yes)
			)
		)
		(property "Author" "Antmicro"
			(at 189.23 52.07 0)
			(effects
				(font
					(size 1.27 1.27)
					(thickness 0.15)
				)
				(justify left bottom)
				(hide yes)
			)
		)
		(property "Val" "100n"
			(at 163.83 72.39 90)
			(effects
				(font
					(size 1.27 1.27)
					(thickness 0.15)
				)
				(justify right)
			)
		)
		(property "Voltage" "50V"
			(at 191.77 52.07 0)
			(effects
				(font
					(size 1.27 1.27)
				)
				(justify left bottom)
				(hide yes)
			)
		)
		(property "Dielectric" "X5R"
			(at 194.31 52.07 0)
			(effects
				(font
					(size 1.27 1.27)
				)
				(justify left bottom)
				(hide yes)
			)
		)
		(property "Public" ""
			(at 196.85 52.07 0)
			(effects
				(font
					(size 1.27 1.27)
				)
				(justify left bottom)
				(hide yes)
			)
		)
		(pin "1"
		)
		(pin "2"
		)
		(instances
			(project "polarfire-som"
				(path ""
					(reference "C73")
					(unit 1)
				)
			)
		)
	)
	(symbol
		(lib_id "antmicroResistors0402:R_49k9_0402")
		(at 237.49 82.55 90)
		(unit 1)
		(exclude_from_sim no)
		(in_bom yes)
		(on_board yes)
		(dnp no)
		(property "Reference" "R31"
			(at 236.22 73.66 0)
			(effects
				(font
					(size 1.27 1.27)
					(thickness 0.15)
				)
				(justify right)
			)
		)
		(property "Value" "R_49k9_0402"
			(at 250.19 62.23 0)
			(effects
				(font
					(size 1.27 1.27)
					(thickness 0.15)
				)
				(justify left bottom)
				(hide yes)
			)
		)
		(property "Footprint" "antmicro-footprints:R_0402_1005Metric"
			(at 252.73 62.23 0)
			(effects
				(font
					(size 1.27 1.27)
					(thickness 0.15)
				)
				(justify left bottom)
				(hide yes)
			)
		)
		(property "Datasheet" "https://www.bourns.com/docs/product-datasheets/cr.pdf"
			(at 255.27 62.23 0)
			(effects
				(font
					(size 1.27 1.27)
					(thickness 0.15)
				)
				(justify left bottom)
				(hide yes)
			)
		)
		(property "Description" "SMD Chip Resistor, 49.9 kohm, ± 1%, 63 mW, 0402 [1005 Metric], Thick Film, General Purpose"
			(at 237.49 82.55 0)
			(effects
				(font
					(size 1.27 1.27)
				)
				(hide yes)
			)
		)
		(property "MPN" "CR0402-FX-4992GLF"
			(at 257.81 62.23 0)
			(effects
				(font
					(size 1.27 1.27)
					(thickness 0.15)
				)
				(justify left bottom)
				(hide yes)
			)
		)
		(property "Manufacturer" "Bourns"
			(at 260.35 62.23 0)
			(effects
				(font
					(size 1.27 1.27)
					(thickness 0.15)
				)
				(justify left bottom)
				(hide yes)
			)
		)
		(property "License" "Apache-2.0"
			(at 262.89 62.23 0)
			(effects
				(font
					(size 1.27 1.27)
					(thickness 0.15)
				)
				(justify left bottom)
				(hide yes)
			)
		)
		(property "Author" "Antmicro"
			(at 265.43 62.23 0)
			(effects
				(font
					(size 1.27 1.27)
					(thickness 0.15)
				)
				(justify left bottom)
				(hide yes)
			)
		)
		(property "Val" "49k9"
			(at 236.22 82.55 0)
			(effects
				(font
					(size 1.27 1.27)
					(thickness 0.15)
				)
				(justify right)
			)
		)
		(property "Tolerance" "1%"
			(at 247.65 62.23 0)
			(effects
				(font
					(size 1.27 1.27)
				)
				(justify left bottom)
				(hide yes)
			)
		)
		(property "Public" ""
			(at 267.97 62.23 0)
			(effects
				(font
					(size 1.27 1.27)
				)
				(justify left bottom)
				(hide yes)
			)
		)
		(pin "1"
		)
		(pin "2"
		)
		(instances
			(project "polarfire-som"
				(path ""
					(reference "R31")
					(unit 1)
				)
			)
		)
	)
)
